# Barreleye-G2_Tri-mode Expander-DVT-X01-SKU-BOM-X07-20171222_Final.xls.xlsx — SKU1 (bom)
| FOXCONN TECHNOLOGY GROUP |  |  |  |  |  |  |  |  |  |  |  |  |  |  |  |  |  |  |  |
| BILL OF MATERIAL |  |  |  |  |  |  |  |  |  |  |  |  |  |  |  |  |  |  |  |
| REV OF  BOM |  | CUSTOMER |  | <name> |  | CUSTOMER P/N |  | AA P/N：1A42NC400-600-1 | PWA DESCRIPTION |  |  |  | PRODUCT CODE |  |  | PWA  REV |  | DATE |  |
| Sourcing (Single/Sole/Multi) | Critical Commodity (Y or N) | Component Class (1, 2, other) | Customer PSL (Y or N) | Line Item | Item Number | Foxconn P/N | Customer P/N | Part Description | Manufacturer  Full Name | Manufacturer  Part Number | Qty | RoHS Status | Location | CC Qual Build: | Qual by (Customer / ODM ?) | The Date of Change Part or Add 2nd Source | Configuration Identifier | Customer Comments | ODM Comments |
|  |  |  |  | 1 | 1 | 0101FGB00-000-G |  | PCB,Zaius-Tri-mode Expander DVT-X01,Blu,10L,9.134*5.118,G | GOLD CIRCUIT ELECTRONICS LTD. | 0101FGB00-000-G | 1 | G | PCB |  |  |  |  |  |  |
|  |  |  |  |  | 1 | 0101FGB00-000-G |  | PCB,Zaius-Tri-mode Expander DVT-X01,Blu,10L,9.134*5.118,G | ZHUHAI FOUNDER PRINTED CIRCUIT BOARD（HK） DEVELOPMENT LIMITED | 0101FGB00-000-G |  | G |  |  |  |  |  |  |  |
|  |  |  |  | 2 | 2 | 62111EC00-021-G |  | ECAP,680uF,+/-20%,16V,105℃,G,SMD10*10,ESR<=80mOhm | NIPPON CHEMI-CON CORPORATION | EMZA160ADA681MJA0G | 2 | G | CE1,CE2 |  |  |  |  |  |  |
|  |  |  |  | 3 | 3 | 620101T02-015-G | - | CAP,100nF,+/-10%,X7R,16V,G,SMD0402 | MURATA ELEC. NORTH AMERICA | GRM155R71C104K | 35 | G | PSCC1,C1,PFCC2,PELC2,PLTC5,C8,PSRC10,PLTC11,PELC11,PFCC13,PECC15,PECC16,PECC18,PECC19,C223,C225,C226,C229,C231,C393,C394,C395,C396,C397,C411,C413,C610,C611,C612,C968,C970,C1524,C2004,C2180,C2183 |  |  |  |  |  |  |
|  |  |  |  |  | 3 | 620101T00-012-G |  | CAP,100nF,+/-10%,X7R,16V,G,SMD0402 | WALSIN TECHNOLOGY CORPORATION | 0402B104K160CT |  | G |  |  |  |  |  |  |  |
|  |  |  |  |  | 3 | 620101T00-026-G |  | CAP,100nF,+/-10%,X7R,16V,G,SMD0402 | SAMSUNG SEMICONDUCTOR | CL05B104KO5NNNC |  | G |  |  |  |  |  |  |  |
|  |  |  |  |  | 3 | 620101T00-015-G |  | CAP,100nF,+/-10%,X7R,16V,G,SMD0402 | MURATA ELEC. NORTH AMERICA | GRM155R71C104KA88D |  | G |  |  |  |  |  |  |  |
|  |  |  |  | 4 | 4 | 62010BN00-015-G | - | CAP,1uF,+/-10%,X5R,6.3V,G,SMD0402 | MURATA ELEC. NORTH AMERICA | GRM155R60J105K | 3 | G | C2,C4,C5 |  |  |  |  |  |  |
|  |  |  |  |  | 4 | 62010BN00-011-G |  | CAP,1uF,+/-10%,X5R,6.3V,G,SMD0402 | YAGEO CORPORATION COMPONENT | CC0402KRX5R5BB105 |  | G |  |  |  |  |  |  |  |
|  |  |  |  |  | 4 | 62010BN00-012-G |  | CAP,1uF,+/-10%,X5R,6.3V,G,SMD0402 | WALSIN TECHNOLOGY CORPORATION | 0402X105K6R3CT |  | G |  |  |  |  |  |  |  |
|  |  |  |  |  | 4 | 62010BN00-026-G |  | CAP,1uF,+/-10%,X5R,6.3V,G,SMD0402 | SAMSUNG SEMICONDUCTOR | CL05A105KQ5NNNC |  | G |  |  |  |  |  |  |  |
|  |  |  |  |  | 4 | 62010BN00-023-G |  | CAP,1uF,+/-10%,X5R,6.3V,G,SMD0402 | TAIYO ELECTRIC IND.CO.LTD | JMK105BJ105KV |  | G |  |  |  |  |  |  |  |
|  |  |  |  | 5 | 5 | 620106200-015-G | - | CAP,10nF,+/-10%,X7R,16V,G,SMD0402 | MURATA ELEC. NORTH AMERICA | GRM155R71C103K | 33 | G | C3,C6,C7,C25,C30,C39,C44,C49,C54,C61,C62,C69,C70,C77,C78,C85,C86,C93,C94,C101,C102,C109,C110,C117,C118,C125,C126,C133,C134,C141,C142,C149,C150 |  |  |  |  |  |  |
|  |  |  |  |  | 5 | 620106200-012-G |  | CAP,10nF,+/-10%,X7R,16V,G,SMD0402 | WALSIN TECHNOLOGY CORPORATION | 0402B103K160CT |  | G |  |  |  |  |  |  |  |
|  |  |  |  |  | 5 | 620106200-026-G |  | CAP,10nF,+/-10%,X7R,16V,G,SMD0402 | SAMSUNG SEMICONDUCTOR | CL05B103KO5NNNC |  | G |  |  |  |  |  |  |  |
|  |  |  |  |  | 5 | 620106200-023-G |  | CAP,10nF,+/-10%,X7R,16V,G,SMD0402 | TAIYO ELECTRIC IND.CO.LTD | EMK105B7103KV-F |  | G |  |  |  |  |  |  |  |
|  |  |  |  | 6 | 6 | 620108H00-015-G | - | CAP,22uF,+/-20%,X5R,6.3V,G,SMD0805 | MURATA ELEC. NORTH AMERICA | GRM21BR60J226M | 10 | G | C9,C13,C17,C21,C26,C31,C35,C40,C45,C50 |  |  |  |  |  |  |
|  |  |  |  |  | 6 | 620108H04-023-G |  | CAP,22uF,+/-20%,X5R,6.3V,G,SMD0805 | TAIYO ELECTRIC IND.CO.LTD | JMK212BJ226MG-T |  | G |  |  |  |  |  |  |  |
|  |  |  |  |  | 6 | 620108H00-026-G |  | CAP,22uF,+/-20%,X5R,6.3V,G,SMD0805 | SAMSUNG SEMICONDUCTOR | CL21A226MQQNNNE |  | G |  |  |  |  |  |  |  |
|  |  |  |  |  | 6 | 620108H00-011-G |  | CAP,22uF,+/-20%,X5R,6.3V,G,SMD0805 | YAGEO CORPORATION COMPONENT | CC0805MKX5R5BB226 |  | G |  |  |  |  |  |  |  |
|  |  |  |  | 7 | 7 | 62010L000-015-G | - | CAP,10uF,+/-20%,X5R,6.3V,G,SMD0603 | MURATA ELEC. NORTH AMERICA | GRM188R60J106M | 23 | G | C10,C14,C18,C22,C27,C32,C36,C41,C46,C51,C151,C152,C153,C154,C155,C191,C192,C193,C194,C224,C227,C228,C230 |  |  |  |  |  |  |
|  |  |  |  |  | 7 | 62010L000-023-G |  | CAP,10uF,+/-20%,X5R,6.3V,G,SMD0603 | TAIYO ELECTRIC IND.CO.LTD | JMK107BJ106MA-T |  | G |  |  |  |  |  |  |  |
|  |  |  |  |  | 7 | 62010L000-012-G |  | CAP,10uF,+/-20%,X5R,6.3V,G,SMD0603 | WALSIN TECHNOLOGY CORPORATION | 0603X106M6R3CT |  | G |  |  |  |  |  |  |  |
|  |  |  |  |  | 7 | 62010L000-026-G |  | CAP,10uF,+/-20%,X5R,6.3V,G,SMD0603 | SAMSUNG SEMICONDUCTOR | CL10A106MQ8NNNC |  | G |  |  |  |  |  |  |  |
|  |  |  |  |  | 7 | 62010L000-011-G |  | CAP,10uF,+/-20%,X5R,6.3V,G,SMD0603 | YAGEO CORPORATION COMPONENT | CC0603MRX5R5BB106 |  | G |  |  |  |  |  |  |  |
|  |  |  |  | 8 | 8 | 62012NU00-015-G | - | CAP,1uF,+/-10%,X7R,6.3V,G,SMD0402 | MURATA ELEC. NORTH AMERICA | GRM155R70J105KA12D | 22 | G | C11,C15,C19,C23,C28,C33,C37,C42,C47,C52,C57,C65,C73,C81,C89,C97,C105,C113,C121,C129,C137,C145 |  |  |  |  |  |  |
|  |  |  |  |  | 8 | 62012NU00-026-G |  | CAP,1uF,+/-10%,X7R,6.3V,G,SMD0402 | SAMSUNG SEMICONDUCTOR | CL05B105KQ5NQNC |  | G |  |  |  |  |  |  |  |
|  |  |  |  | 9 | 9 | 620103700-015-G | - | CAP,100nF,+/-10%,X7R,10V,G,SMD0402 | MURATA ELEC. NORTH AMERICA | GRM155R71A104K | 106 | G | PSLC10,PSGC10,C12,C16,C20,C24,C29,C34,C38,C43,C48,C53,C58,C59,C60,C66,C67,C68,C74,C75,C76,C82,C83,C84,C90,C91,C92,C98,C99,C100,C106,C107,C108,C114,C115,C116,C122,C123,C124,C130,C131,C132,C138,C139,C140,C146,C147,C148,C161,C162,C163,C164,C165,C166,C167,C168,C169,C170,C171,C172,C173,C174,C175,C176,C177,C178,C179,C180,C181,C182,C183,C184,C185,C186,C187,C188,C189,C190,C199,C200,C201,C202,C203,C204,C205,C206,C207,C208,C209,C210,C211,C212,C213,C214,C215,C216,C217,C218,C219,C220,C221,C222,C415,C2179,C2181,C2182 |  |  |  |  |  |  |
|  |  |  |  |  | 9 | 620103700-012-G |  | CAP,0.1uF,+/-10%,X7R,10V,G,SMD0402 | WALSIN TECHNOLOGY CORPORATION | 0402B104K100CT |  | G |  |  |  |  |  |  |  |
|  |  |  |  |  | 9 | 620103700-023-G |  | CAP,100nF,+/-10%,X7R,10V,G,SMD0402 | TAIYO ELECTRIC IND.CO.LTD | LMK105B7104KV-F |  | G |  |  |  |  |  |  |  |
|  |  |  |  |  | 9 | 620103700-026-G |  | CAP,100nF,+/-10%,X7R,10V,G,SMD0402 | SAMSUNG SEMICONDUCTOR | CL05B104KP5NNNC |  | G |  |  |  |  |  |  |  |
|  |  |  |  | 10 | 10 | 620132700-015-G |  | CAP,100uF,+/-20%,X5R,6.3V,G,SMD0805 | MURATA ELEC. NORTH AMERICA | GRM21BR60J107ME15L | 12 | G | C55,C63,C71,C79,C87,C95,C103,C111,C119,C127,C135,C143 |  |  |  |  |  |  |
|  |  |  |  |  | 10 | 620132700-012-G |  | CAP,100uF,+/-20%,X5R,6.3V,G,SMD0805 | WALSIN TECHNOLOGY CORPORATION | 0805X107M6R3CT |  | G |  |  |  |  |  |  |  |
|  |  |  |  | 11 | 11 | 62012Y400-015-G |  | CAP,22uF,+/-20%,X5R,6.3V,G,SMD0402 | MURATA ELEC. NORTH AMERICA | GRM155R60J226ME11D | 12 | G | C56,C64,C72,C80,C88,C96,C104,C112,C120,C128,C136,C144 |  |  |  |  |  |  |
|  |  |  |  |  | 11 | 62012Y400-026-G |  | CAP,22uF,+/-20%,X5R,6.3V,G,SMD0402 | SAMSUNG SEMICONDUCTOR | CL05A226MQ5N6J8 |  | G |  |  |  |  |  |  |  |
|  |  |  |  |  | 11 | 62012Y400-011-G |  | CAP,22uF,+/-20%,X5R,6.3V,G,SMD0402 | YAGEO CORPORATION COMPONENT | CC0402MRX5R5BB226 |  | G |  |  |  |  |  |  |  |
|  |  |  |  |  | 11 | 62012Y400-012-G |  | CAP,22uF,+/-20%,X5R,6.3V,G,SMD0402 | WALSIN TECHNOLOGY CORPORATION | 0402X226M6R3CT |  | G |  |  |  |  |  |  |  |
|  |  |  |  | 12 | 12 | 62010P501-015-G | - | CAP,1nF,+/-10%,X7R,16V,G,SMD0402 | MURATA ELEC. NORTH AMERICA | GRM155R71C102KA01D | 9 | G | C156,C157,C158,C159,C160,C195,C196,C197,C198 |  |  |  |  |  |  |
|  |  |  |  |  | 12 | 62010P500-023-G |  | CAP,1nF,+/-10%,X7R,16V,G,SMD0402 | TAIYO ELECTRIC IND.CO.LTD | EMK105B7102KV-F |  | G |  |  |  |  |  |  |  |
|  |  |  |  |  | 12 | 62010P500-026-G |  | CAP,1nF,+/-10%,X7R,16V,G,SMD0402 | SAMSUNG SEMICONDUCTOR | CL05B102KO5NNNC |  | G |  |  |  |  |  |  |  |
|  |  |  |  | 13 | 13 | 62012QF00-023-G |  | CAP,10nF,+/-10%,X7R,16V,G,SMD0201 | TAIYO ELECTRIC IND.CO.LTD | EMK063B7103KP-F | 212 | G | C233,C234,C235,C236,C237,C238,C239,C240,C241,C242,C243,C244,C245,C246,C247,C248,C249,C250,C251,C252,C253,C254,C255,C256,C257,C258,C259,C260,C261,C262,C263,C264,C297,C298,C299,C300,C301,C302,C303,C304,C305,C306,C307,C308,C309,C310,C311,C312,C313,C314,C315,C316,C317,C318,C319,C320,C321,C322,C323,C324,C325,C326,C327,C328,C329,C330,C331,C332,C333,C334,C335,C336,C337,C338,C339,C340,C341,C342,C343,C344,C345,C346,C347,C348,C349,C350,C351,C352,C353,C354,C355,C356,C357,C358,C359,C360,C361,C362,C363,C364,C365,C366,C367,C368,C369,C370,C371,C372,C373,C374,C375,C376,C377,C378,C379,C380,C381,C382,C383,C384,C385,C386,C387,C388,C389,C390,C391,C392,C640,C641,C642,C643,C644,C645,C646,C647,C648,C649,C650,C651,C652,C653,C654,C655,C656,C657,C658,C659,C660,C661,C662,C663,C664,C665,C674,C675,C676,C677,C678,C679,C680,C681,C682,C725,C726,C727,C728,C729,C730,C731,C732,C733,C734,C735,C736,C737,C738,C739,C740,C741,C742,C743,C744,C745,C746,C747,C748,C749,C750,C751,C752,C753,C754,C755,C756,C757,C758,C759,C775,C776,C777,C778,C779,C780,C781,C797,C798,C799,C800,C801,C802,C803 |  |  |  |  |  |  |
|  |  |  |  |  | 13 | 62012QF00-012-G |  | CAP,10nF,+/-10%,X7R,16V,G,SMD0201 | WALSIN TECHNOLOGY CORPORATION | 0201B103K160CT |  | G |  |  |  |  |  |  |  |
|  |  |  |  |  | 13 | 62012QF00-026-G |  | CAP,10nF,+/-10%,X7R,16V,G,SMD0201 | SAMSUNG SEMICONDUCTOR | CL03B103KO3NNNC |  | G |  |  |  |  |  |  |  |
|  |  |  |  | 14 | 14 | 62012GG00-015-G | - | CAP,10uF,+/-10%,X7S,25V,G,SMD0805 | MURATA ELEC. NORTH AMERICA | GRM21BC71E106K | 7 | G | PLTC1,PSRC3,PSLC3,PSGC3,C398,C399,PSCC3004 |  |  |  |  |  |  |
|  |  |  |  |  | 14 | 62012GG00-012-G |  | CAP,10uF,+/-10%,X7S,25V,G,SMD0805 | WALSIN TECHNOLOGY CORPORATION | 0805A106K250CT |  | G |  |  |  |  |  |  |  |
|  |  |  |  | 15 | 15 | 62012A400-015-G | - | CAP,100nF,+/-10%,X7R,25V,G,SMD0402 | MURATA ELEC. NORTH AMERICA | GRM155R71E104KE14D | 17 | G | PSRC1,PSLC1,PSGC1,PELC3,PLTC4,PFCC4,PELC4,PSRC6,PSLC6,PSGC6,PELC10,PFCC11,PECC13,C400,C404,PSCC3002,PSCC3008 |  |  |  |  |  |  |
|  |  |  |  |  | 15 | 62012A400-023-G |  | CAP,100nF,+/-10%,X7R,25V,G,SMD0402 | TAIYO ELECTRIC IND.CO.LTD | TMK105B7104KV-FR |  | G |  |  |  |  |  |  |  |
|  |  |  |  |  | 15 | 62012A400-026-G |  | CAP,100nF,+/-10%,X7R,25V,G,SMD0402 | SAMSUNG SEMICONDUCTOR | CL05B104KA5NNNC |  | G |  |  |  |  |  |  |  |
|  |  |  |  |  | 15 | 62012A400-012-G |  | CAP,100nF,+/-10%,X7R,25V,G,SMD0402 | WALSIN TECHNOLOGY CORPORATION | 0402B104K250CT |  | G |  |  |  |  |  |  |  |
|  |  |  |  | 16 | 16 | 620109N00-015-G |  | CAP,2.2uF,+/-10%,X7R,10V,G,SMD0603 | MURATA ELEC. NORTH AMERICA | GRM188R71A225K | 1 | G | C401 |  |  |  |  |  |  |
|  |  |  |  |  | 16 | 620109N00-023-G |  | CAP,2.2uF,+/-10%,X7R,10V,G,SMD0603 | TAIYO ELECTRIC IND.CO.LTD | LMK107B7225KA-T |  | G |  |  |  |  |  |  |  |
|  |  |  |  |  | 16 | 620109N00-026-G |  | CAP,2.2uF,+/-10%,X7R,10V,G,SMD0603 | SAMSUNG SEMICONDUCTOR | CL10B225KP8NNNC |  | G |  |  |  |  |  |  |  |
|  |  |  |  | 17 | 17 | 62012H100-015-G | - | CAP,10uF,+/-20%,X6S,10V,G,SMD0603 | MURATA ELEC. NORTH AMERICA | GRM188C81A106M | 3 | G | PSRC16,C402,C403 |  |  |  |  |  |  |
|  |  |  |  |  | 17 | 62012H100-023-G |  | CAP,10uF,+/-20%,X6S,10V,G,SMD0603 | TAIYO ELECTRIC IND.CO.LTD | LMK107BC6106MA-T |  | G |  |  |  |  |  |  |  |
|  |  |  |  |  | 17 | 62012H100-026-G |  | CAP,10uF,+/-20%,X6S,10V,G,SMD0603 | SAMSUNG SEMICONDUCTOR | CL10X106MP8NRNC |  | G |  |  |  |  |  |  |  |
|  |  |  |  | 18 | 18 | 620108J00-015-G | - | CAP,100uF,+/-20%,X5R,6.3V,G,SMD1210 | MURATA ELEC. NORTH AMERICA | GRM32ER60J107M | 1 | G | C406 |  |  |  |  |  |  |
|  |  |  |  |  | 18 | 620108J00-012-G |  | CAP,100uF,+/-20%,X5R,6.3V,G,SMD1210 | WALSIN TECHNOLOGY CORPORATION | 1210X107M6R3CT |  | G |  |  |  |  |  |  |  |
|  |  |  |  |  | 18 | 620108J00-011-G |  | CAP,100uF,+/-20%,X5R,6.3V,G,SMD1210 | YAGEO CORPORATION COMPONENT | CC1210MKX5R5BB107 |  | G |  |  |  |  |  |  |  |
|  |  |  |  |  | 18 | 620108J00-026-G |  | CAP,100uF,+/-20%,X5R,6.3V,G,SMD1210 | SAMSUNG SEMICONDUCTOR | CL32A107MQVNNNE |  | G |  |  |  |  |  |  |  |
|  |  |  |  |  | 18 | 620108J07-023-G |  | CAP,100uF,+/-20%,X5R,6.3V,G,SMD1210 | TAIYO ELECTRIC IND.CO.LTD | JMK325ABJ107MM-T |  | G |  |  |  |  |  |  |  |
|  |  |  |  | 19 | 19 | 620100A00-015-G | - | CAP,10uF,+/-10%,X5R,16V,G,SMD1206 | MURATA ELEC. NORTH AMERICA | GRM31CR61C106K | 8 | G | C409,C410,C412,C414,C966,C967,C969,C971 |  |  |  |  |  |  |
|  |  |  |  |  | 19 | 620100A00-026-G |  | CAP,10uF,+/-10%,X5R,16V,G,SMD1206 | SAMSUNG SEMICONDUCTOR | CL31A106KOHNNNE |  | G |  |  |  |  |  |  |  |
|  |  |  |  |  | 19 | 620100A03-023-G |  | CAP,10uF,+/-10%,X5R,16V,G,SMD1206 | TAIYO ELECTRIC IND.CO.LTD | EMK316BJ106KL-T |  | G |  |  |  |  |  |  |  |
|  |  |  |  |  | 19 | 620100A00-012-G |  | CAP,10uF,+/-10%,X5R,16V,G,SMD1206 | WALSIN TECHNOLOGY CORPORATION | 1206X106K160CT |  | G |  |  |  |  |  |  |  |
|  |  |  |  |  | 19 | 620100A00-011-G |  | CAP,10uF,+/-10%,X5R,16V,G,SMD1206 | YAGEO CORPORATION COMPONENT | CC1206KKX5R7BB106 |  | G |  |  |  |  |  |  |  |
|  |  |  |  | 20 | 20 | 62011DF01-015-G | - | CAP,220nF,+/-10%,X7R,16V,G,SMD0402 | MURATA ELEC. NORTH AMERICA | GRM155R71C224K | 288 | G | C416,C417,C418,C419,C420,C421,C422,C423,C424,C425,C426,C427,C428,C429,C430,C431,C432,C433,C434,C435,C436,C437,C438,C439,C440,C441,C442,C443,C444,C445,C446,C447,C448,C449,C450,C451,C452,C453,C454,C455,C456,C457,C458,C459,C460,C461,C462,C463,C464,C465,C466,C467,C468,C469,C470,C471,C472,C473,C474,C475,C476,C477,C478,C479,C480,C481,C482,C485,C488,C489,C490,C491,C496,C497,C498,C499,C504,C505,C506,C507,C512,C513,C514,C515,C516,C517,C518,C519,C520,C521,C522,C523,C524,C525,C526,C527,C528,C529,C530,C531,C532,C533,C534,C535,C536,C537,C538,C539,C540,C541,C542,C543,C544,C545,C550,C551,C552,C553,C554,C555,C560,C561,C562,C563,C568,C569,C570,C571,C576,C577,C578,C582,C584,C585,C586,C587,C592,C593,C594,C595,C600,C601,C602,C603,C822,C823,C824,C825,C826,C827,C828,C829,C830,C831,C832,C833,C834,C835,C836,C837,C838,C839,C840,C841,C842,C843,C844,C845,C846,C847,C848,C849,C850,C851,C852,C853,C854,C855,C856,C857,C858,C859,C860,C862,C863,C864,C865,C866,C867,C868,C869,C870,C871,C872,C873,C874,C875,C876,C877,C878,C879,C880,C881,C882,C883,C884,C885,C886,C887,C888,C889,C890,C891,C892,C893,C894,C895,C896,C897,C898,C899,C900,C901,C910,C911,C912,C913,C914,C915,C916,C917,C918,C919,C920,C921,C922,C923,C924,C925,C926,C927,C928,C929,C930,C931,C932,C933,C934,C935,C936,C937,C938,C939,C940,C941,C942,C943,C944,C945,C946,C947,C948,C949,C950,C951,C952,C953,C954,C955,C956,C957,C958,C959,C960,C961,C962,C963,C964,C965,C2115,C2136,C2138,C2141,C2142,C2144,C2145,C2146,C2166 |  |  |  |  |  |  |
|  |  |  |  |  | 20 | 62011DF00-026-G |  | CAP,220nF,+/-10%,X7R,16V,G,SMD0402 | SAMSUNG SEMICONDUCTOR | CL05B224KO5NNNC |  | G |  |  |  |  |  |  |  |
|  |  |  |  |  | 20 | 62011DF00-023-G |  | CAP,220nF,+/-10%,X7R,16V,G,SMD0402 | TAIYO ELECTRIC IND.CO.LTD | EMK105B7224KV-FR |  | G |  |  |  |  |  |  |  |
|  |  |  |  | 21 | 21 | 620119R04-015-G | - | CAP,22uF,+/-20%,X6S,4V,G,SMD0805 | MURATA ELEC. NORTH AMERICA | GRM21BC80G226M | 35 | G | PSLC7,PSGC7,PSLC8,PSGC8,PSLC11,PSGC11,PSLC12,PSGC12,PFCC14,PSLC15,PSGC15,PFCC15,PFCC16,PFCC17,PFCC18,PFCC20,PFCC21,PFCC22,PFCC23,PFCC24,PFCC25,PFCC26,PFCC27,PFCC28,PFCC29,PECC29,PFCC30,PECC30,PFCC31,PFCC32,PFCC33,PFCC34,PECC40,PECC41,C609 |  |  |  |  |  |  |
|  |  |  |  |  | 21 | 620119R01-015-G |  | CAP,22uF,+/-20%,X6S,4V,G,SMD0805 | MURATA ELEC. NORTH AMERICA | GRM21BC80G226ME39K |  | G |  |  |  |  |  |  |  |
|  |  |  |  |  | 21 | 620119R00-023-G |  | CAP,22uF,+/-20%,X6S,4V,G,SMD0805 | TAIYO ELECTRIC IND.CO.LTD | AMK212C6226MG-T |  | G |  |  |  |  |  |  |  |
|  |  |  |  |  | 21 | 620119R00-026-G |  | CAP,22uF,+/-20%,X6S,4V,G,SMD0805 | SAMSUNG SEMICONDUCTOR | CL21X226MRQNNNE |  | G |  |  |  |  |  |  |  |
|  |  |  |  | 22 | 22 | 62012C800-015-G | - | CAP,100nF,+/-10%,X5R,16V,G,SMD0201 | MURATA ELEC. NORTH AMERICA | GRM033R61C104K | 82 | G | C614,C615,C616,C617,C618,C619,C620,C621,C622,C623,C624,C625,C626,C627,C628,C629,C630,C631,C632,C633,C634,C635,C636,C637,C638,C639,C666,C667,C668,C669,C670,C671,C672,C673,C691,C692,C693,C694,C695,C696,C697,C698,C699,C700,C701,C702,C703,C704,C705,C706,C707,C708,C709,C710,C711,C712,C713,C714,C715,C716,C717,C718,C719,C720,C721,C722,C723,C724,C768,C769,C770,C771,C772,C773,C774,C790,C791,C792,C793,C794,C795,C796 |  |  |  |  |  |  |
|  |  |  |  |  | 22 | 62012C800-023-G |  | CAP,100nF,+/-10%,X5R,16V,G,SMD0201 | TAIYO ELECTRIC IND.CO.LTD | EMK063BJ104KP-F |  | G |  |  |  |  |  |  |  |
|  |  |  |  |  | 22 | 62012C800-026-G |  | CAP,100nF,+/-10%,X5R,16V,G,SMD0201 | SAMSUNG SEMICONDUCTOR | CL03A104KO3NNNC |  | G |  |  |  |  |  |  |  |
|  |  |  |  |  | 22 | 62012C800-011-G |  | CAP,100nF,+/-10%,X5R,16V,G,SMD0201 | YAGEO CORPORATION COMPONENT | CC0201KRX5R7BB104 |  | G |  |  |  |  |  |  |  |
|  |  |  |  | 23 | 23 | 620105400-015-G |  | CAP,1uF,+/-10%,X7R,16V,G,SMD0603 | MURATA ELEC. NORTH AMERICA | GRM188R71C105K | 25 | G | PFCC12,C683,C684,C685,C686,C687,C688,C689,C690,C760,C761,C762,C763,C764,C765,C766,C767,C782,C783,C784,C785,C786,C787,C788,C789 |  |  |  |  |  |  |
|  |  |  |  |  | 23 | 620105400-012-G |  | CAP,1uF,+/-10%,X7R,16V,G,SMD0603 | WALSIN TECHNOLOGY CORPORATION | 0603B105K160CT |  | G |  |  |  |  |  |  |  |
|  |  |  |  |  | 23 | 620105400-011-G |  | CAP,1uF,+/-10%,X7R,16V,G,SMD0603 | YAGEO CORPORATION COMPONENT | CC0603KRX7R7BB105 |  | G |  |  |  |  |  |  |  |
|  |  |  |  |  | 23 | 620105400-026-G |  | CAP,1uF,+/-10%,X7R,16V,G,SMD0603 | SAMSUNG SEMICONDUCTOR | CL10B105KO8NNNC |  | G |  |  |  |  |  |  |  |
|  |  |  |  |  | 23 | 620105400-023-G |  | CAP,1uF,+/-10%,X7R,16V,G,SMD0603 | TAIYO ELECTRIC IND.CO.LTD | EMK107B7105KA-T |  | G |  |  |  |  |  |  |  |
|  |  |  |  | 24 | 24 | 620100L00-015-G | - | CAP,22pF,+/-5%,NPO(C0G),50V,G,SMD0402 | MURATA ELEC. NORTH AMERICA | GRM1555C1H220J | 2 | G | C806,C807 |  |  |  |  |  |  |
|  |  |  |  |  | 24 | 620100L08-012-G |  | CAP,22pF,+/-5%,NPO(C0G),50V,G,SMD0402 | WALSIN TECHNOLOGY CORPORATION | 0402N220J500CT |  | G |  |  |  |  |  |  |  |
|  |  |  |  |  | 24 | 620100L00-023-G |  | CAP,22pF,+/-5%,NPO(C0G),50V,G,SMD0402 | TAIYO ELECTRIC IND.CO.LTD | UMK105CG220JV-F |  | G |  |  |  |  |  |  |  |
|  |  |  |  |  | 24 | 620100L00-026-G |  | CAP,22pF,+/-5%,NPO(C0G),50V,G,SMD0402 | SAMSUNG SEMICONDUCTOR | CL05C220JB5NNNC |  | G |  |  |  |  |  |  |  |
|  |  |  |  | 25 | 25 | 620102U00-015-G | - | CAP,100nF,+/-10%,X5R,10V,G,SMD0402 | MURATA ELEC. NORTH AMERICA | GRM155R61A104K | 3 | G | C808,C2171,C2173 |  |  |  |  |  |  |
|  |  |  |  |  | 25 | 620102U00-023-G |  | CAP,100nF,+/-10%,X5R,10V,G,SMD0402 | TAIYO ELECTRIC IND.CO.LTD | LMK105BJ104KV-F |  | G |  |  |  |  |  |  |  |
|  |  |  |  |  | 25 | 620102U00-011-G |  | CAP,100nF,+/-10%,X5R,10V,G,SMD0402 | YAGEO CORPORATION COMPONENT | CC0402KRX5R6BB104 |  | G |  |  |  |  |  |  |  |
|  |  |  |  |  | 25 | 620102U00-026-G |  | CAP,100nF,+/-10%,X5R,10V,G,SMD0402 | SAMSUNG SEMICONDUCTOR | CL05A104KP5NNNC |  | G |  |  |  |  |  |  |  |
|  |  |  |  |  | 25 | 620102U00-012-G |  | CAP,100nF,+/-10%,X5R,10V,G,SMD0402 | WALSIN TECHNOLOGY CORPORATION | 0402X104K100CT |  | G |  |  |  |  |  |  |  |
|  |  |  |  | 26 | 26 | 62011CA01-015-G |  | CAP,10uF,+/-10%,X5R,10V,G,SMD0603 | MURATA ELEC. NORTH AMERICA | GRM188R61A106K | 1 | G | C2170 |  |  |  |  |  |  |
|  |  |  |  |  | 26 | 62011CA00-026-G |  | CAP,10uF,+/-10%,X5R,10V,G,SMD0603 | SAMSUNG SEMICONDUCTOR | CL10A106KP8NNNC |  | G |  |  |  |  |  |  |  |
|  |  |  |  |  | 26 | 62011CA00-011-G |  | CAP,10uF,+/-10%,X5R,10V,G,SMD0603 | YAGEO CORPORATION COMPONENT | CC0603KRX5R6BB106 |  | G |  |  |  |  |  |  |  |
|  |  |  |  |  | 26 | 62011CA00-012-G |  | CAP,10uF,+/-10%,X5R,10V,G,SMD0603 | WALSIN TECHNOLOGY CORPORATION | 0603X106K100CT |  | G |  |  |  |  |  |  |  |
|  |  |  |  | 27 | 27 | 62010JJ00-015-G | - | CAP,1uF,+/-10%,X5R,10V,G,SMD0402 | MURATA ELEC. NORTH AMERICA | GRM155R61A105K | 2 | G | PECC8,C2172 |  |  |  |  |  |  |
|  |  |  |  |  | 27 | 62010JJ01-023-G |  | CAP,1uF,+/-10%,X5R,10V,G,SMD0402 | TAIYO ELECTRIC IND.CO.LTD | LMK105BJ105KV-F |  | G |  |  |  |  |  |  |  |
|  |  |  |  |  | 27 | 62010JJ00-011-G |  | CAP,1uF,+/-10%,X5R,10V,G,SMD0402 | YAGEO CORPORATION COMPONENT | CC0402KRX5R6BB105 |  | G |  |  |  |  |  |  |  |
|  |  |  |  |  | 27 | 62010JJ00-012-G |  | CAP,1uF,+/-10%,X5R,10V,G,SMD0402 | WALSIN TECHNOLOGY CORPORATION | 0402X105K100CT |  | G |  |  |  |  |  |  |  |
|  |  |  |  |  | 27 | 62010JJ00-026-G |  | CAP,1uF,+/-10%,X5R,10V,G,SMD0402 | SAMSUNG SEMICONDUCTOR | CL05A105KP5NNNC |  | G |  |  |  |  |  |  |  |
|  |  |  |  | 28 | 28 | 520308900-214-G | - | DIODE,Schottky,BAR43FILM,30V,0.1A,G,SOT23-3,SMD | ST MICRO ELECTRONICS,INC | BAR43FILM | 7 | G | D1,D2,D3,D4,D5,D6,D7 |  |  |  |  |  |  |
|  |  |  |  | 29 | 29 | 521107T00-289-G | KX549 | LED,Gre,LTST-C190KGKT,2.4V,30mA,G,SMD0603 | LITE-ON TECHNOLOGY CORPORATION | LTST-C190KGKT | 29 | G | LED_HB1,LED_BLK1,LED_SASEXP_P0V9,LED_SW1_P0,LED_SW1_P1,LED_SW1_P2,LED_SW1_P3,LED_SW1_P4,LED_SW1_P5,LED_SW1_P6,LED_SW1_P7,LED_SW1_P8,LED_SW1_P9,LED_SW1_P10,LED_SW1_P11,LED_SW1_P12,LED_SW1_P13,LED_SW1_P14,LED_SW1_P15,LED_SW1_P16,LED_SW1_P17,LED_SW1_P18,LED_SW1_P19,LED_SW1_P20,LED_SW1_P21,LED_SW1_P22,LED_SW1_P23,LED_PEX9797_PG,LED_EXP_BP_PG |  |  |  |  |  |  |
|  |  |  |  | 30 | 30 | 720100W00-015-G |  | FB,330 Ohm@100MHz,+/-25%,1.5A,90mOhm,G,SMD0805 | MURATA ELEC. NORTH AMERICA | BLM21PG331SN1D | 1 | G | L1 |  |  |  |  |  |  |
|  |  |  |  | 31 | 31 | 720103500-016-G |  | FB,600 Ohm@100MHz,+/-25%,2A,100mOhm,G,SMD0805 | TDK ELECTRONICS EUROPE GMBH | MPZ2012S601AT | 10 | G | L2,L3,L4,L5,L6,L7,L8,L9,L10,L11 |  |  |  |  |  |  |
|  |  |  |  | 32 | 32 | 720103401-059-G |  | FB,Multilayer,20mOhm,30Ohm@100MHz,+/-25%,5A,,SMD0805,G | TAI-TECH ADVANCED ELECTRONICS CO., LTD. | HCB2012VF-300T50 | 12 | G | L12,L13,L14,L15,L16,L17,L18,L19,L20,L21,L22,L23 |  |  |  |  |  |  |
|  |  |  |  | 33 | 33 | 720101L00-015-G | R8955 | FB,600 Ohm@100MHz,+/-25%,200mA,500mOhm,G,SMD0603 | MURATA ELEC. NORTH AMERICA | BLM18AG601SN1D | 1 | G | L24 |  |  |  |  |  |  |
|  |  |  |  | 34 | 34 | 62120BA00-022-G |  | SPEA,CAP,180uF,+/-20%,16V,105C,G,SMD6.3*5.9,ESR<=22mOhm | SANYO ELECTRIC CO., LTD. | 16SVPF180M | 1 | G | PECCE1 |  |  |  |  |  |  |
|  |  |  |  | 35 | 35 | 62120ES00-024-G | - | SPEA CAP,560uF,+/-20%,2V,105C,G,SMD2816,ESR<=3mOhm | PANASONIC INDUSTRIAL CO.,LTD. | EEFGX0D561L | 4 | G | PECCE3,PECCE4,PECCE5,PECCE6 |  |  |  |  |  |  |
|  |  |  |  | 36 | 36 | 620103K00-015-G | - | CAP,1nF,+/-10%,X7R,50V,G,SMD0402 | MURATA ELEC. NORTH AMERICA | GRM155R71H102K | 3 | G | PECC1,PELC17,PFCC19 |  |  |  |  |  |  |
|  |  |  |  |  | 36 | 620103K00-012-G |  | CAP,1nF,+/-10%,X7R,50V,G,SMD0402 | WALSIN TECHNOLOGY CORPORATION | 0402B102K500CT |  | G |  |  |  |  |  |  |  |
|  |  |  |  |  | 36 | 620103K00-026-G |  | CAP,1nF,+/-10%,X7R,50V,G,SMD0402 | SAMSUNG SEMICONDUCTOR | CL05B102KB5NNNC |  | G |  |  |  |  |  |  |  |
|  |  |  |  |  | 36 | 620103K00-023-G |  | CAP,1nF,+/-10%,X7R,50V,G,SMD0402 | TAIYO ELECTRIC IND.CO.LTD | UMK105B7102KV-F |  | G |  |  |  |  |  |  |  |
|  |  |  |  | 37 | 37 | 62010FY00-015-G | - | CAP,1.5nF,+/-10%,X7R,50V,G,SMD0402 | MURATA ELEC. NORTH AMERICA | GRM155R71H152K | 1 | G | PECC2 |  |  |  |  |  |  |
|  |  |  |  |  | 37 | 62010FY00-012-G |  | CAP,1.5nF,+/-10%,X7R,50V,G,SMD0402 | WALSIN TECHNOLOGY CORPORATION | 0402B152K500CT |  | G |  |  |  |  |  |  |  |
|  |  |  |  |  | 37 | 62010FY00-026-G |  | CAP,1.5nF,+/-10%,X7R,50V,G,SMD0402 | SAMSUNG SEMICONDUCTOR | CL05B152KB5NNNC |  | G |  |  |  |  |  |  |  |
|  |  |  |  |  | 37 | 62010FY00-023-G |  | CAP,1.5nF,+/-10%,X7R,50V,G,SMD0402 | TAIYO ELECTRIC IND.CO.LTD | UMK105B7152KV-F |  | G |  |  |  |  |  |  |  |
|  |  |  |  | 38 | 38 | 620103U00-015-G | - | CAP,470pF,+/-10%,X7R,50V,G,SMD0402 | MURATA ELEC. NORTH AMERICA | GRM155R71H471K | 1 | G | PECC4 |  |  |  |  |  |  |
|  |  |  |  |  | 38 | 620103U00-012-G |  | CAP,470pF,+/-10%,X7R,50V,G,SMD0402 | WALSIN TECHNOLOGY CORPORATION | 0402B471K500CT |  | G |  |  |  |  |  |  |  |
|  |  |  |  |  | 38 | 620103U00-026-G |  | CAP,470pF,+/-10%,X7R,50V,G,SMD0402 | SAMSUNG SEMICONDUCTOR | CL05B471KB5NNNC |  | G |  |  |  |  |  |  |  |
|  |  |  |  |  | 38 | 620103U00-023-G |  | CAP,470pF,+/-10%,X7R,50V,G,SMD0402 | TAIYO ELECTRIC IND.CO.LTD | UMK105B7471KV-F |  | G |  |  |  |  |  |  |  |
|  |  |  |  | 39 | 39 | 620114T00-015-G | - | CAP,330nF,+/-10%,X5R,10V,G,SMD0402 | MURATA ELEC. NORTH AMERICA | GRM155R61A334K | 1 | G | PECC7 |  |  |  |  |  |  |
|  |  |  |  |  | 39 | 620114T00-012-G |  | CAP,330nF,+/-10%,X5R,10V,G,SMD0402 | WALSIN TECHNOLOGY CORPORATION | 0402X334K100CT |  | G |  |  |  |  |  |  |  |
|  |  |  |  |  | 39 | 620114T00-011-G |  | CAP,330nF,+/-10%,X5R,10V,G,SMD0402 | YAGEO CORPORATION COMPONENT | CC0402KRX5R6BB334 |  | G |  |  |  |  |  |  |  |
|  |  |  |  | 40 | 40 | 62012GE00-015-G | - | CAP,4.7uF,+/-20%,X7S,10V,G,SMD0603 | MURATA ELEC. NORTH AMERICA | GRM188C71A475M | 1 | G | PECC9 |  |  |  |  |  |  |
|  |  |  |  |  | 40 | 62012T800-023-G |  | CAP,4.7uF,+/-10%,X7S,10V,G,SMD0603 | TAIYO ELECTRIC IND.CO.LTD | LDK107BC7475KA-T |  | G |  |  |  |  |  |  |  |
|  |  |  |  | 41 | 41 | 62011F100-015-G |  | CAP,1uF,+/-10%,X7R,25V,G,SMD0603 | MURATA ELEC. NORTH AMERICA | GRM188R71E105K | 2 | G | PFCC3,PECC10 |  |  |  |  |  |  |
|  |  |  |  |  | 41 | 62011F100-023-G |  | CAP,1uF,+/-10%,X7R,25V,G,SMD0603 | TAIYO ELECTRIC IND.CO.LTD | TMK107B7105KA-T |  | G |  |  |  |  |  |  |  |
|  |  |  |  |  | 41 | 62011F100-026-G |  | CAP,1uF,+/-10%,X7R,25V,G,SMD0603 | SAMSUNG SEMICONDUCTOR | CL10B105KA8NNNC |  | G |  |  |  |  |  |  |  |
|  |  |  |  | 42 | 42 | 62010L800-015-G | - | CAP,1nF,+/-5%,NPO(C0G),50V,G,SMD0402 | MURATA ELEC. NORTH AMERICA | GRM1555C1H102J | 3 | G | PSCC5,PECC11,PECC12 |  |  |  |  |  |  |
|  |  |  |  |  | 42 | 62010L800-012-G |  | CAP,1nF,+/-5%,NPO(C0G),50V,G,SMD0402 | WALSIN TECHNOLOGY CORPORATION | 0402N102J500CT |  | G |  |  |  |  |  |  |  |
|  |  |  |  |  | 42 | 62010L800-026-G |  | CAP,1nF,+/-5%,NPO(C0G),50V,G,SMD0402 | SAMSUNG SEMICONDUCTOR | CL05C102JB5NNNC |  | G |  |  |  |  |  |  |  |
|  |  |  |  | 43 | 43 | 62012P100-015-G |  | CAP,2.2uF,+/-20%,X7S,10V,G,SMD0402 | MURATA ELEC. NORTH AMERICA | GRM155C71A225M | 5 | G | PSRC5,PSLC5,PSGC5,PECC14,PECC17 |  |  |  |  |  |  |
|  |  |  |  |  | 43 | 62012P100-012-G |  | CAP,2.2uF,+/-20%,X7S,10V,G,SMD0402 | WALSIN TECHNOLOGY CORPORATION | 0402A225M100CT |  | G |  |  |  |  |  |  |  |
|  |  |  |  | 44 | 44 | 620109700-015-G |  | CAP,3.3nF,+/-10%,X7R,50V,G,SMD0402 | MURATA ELEC. NORTH AMERICA | GRM155R71H332K | 7 | G | PLTC6,PECC20,PECC21,PECC22,PECC31,PECC32,PECC33 |  |  |  |  |  |  |
|  |  |  |  |  | 44 | 620109700-012-G |  | CAP,3.3nF,+/-10%,X7R,50V,G,SMD0402 | WALSIN TECHNOLOGY CORPORATION | 0402B332K500CT |  | G |  |  |  |  |  |  |  |
|  |  |  |  |  | 44 | 620109700-026-G |  | CAP,3.3nF,+/-10%,X7R,50V,G,SMD0402 | SAMSUNG SEMICONDUCTOR | CL05B332KB5NNNC |  | G |  |  |  |  |  |  |  |
|  |  |  |  | 45 | 45 | 62011HS01-015-G |  | CAP,10uF,+/-10%,X7R,25V,G,SMD1206 | MURATA ELEC. NORTH AMERICA | GRM31CR71E106K | 21 | G | PFCC5,PELC5,PFCC6,PELC6,PFCC7,PELC7,PFCC8,PELC8,PFCC9,PECC23,PECC24,PECC25,PECC26,PECC27,PECC28,PECC34,PECC35,PECC36,PECC37,PECC38,PECC39 |  |  |  |  |  |  |
|  |  |  |  |  | 45 | 62011HS00-026-G |  | CAP,10uF,+/-10%,X7R,25V,G,SMD1206 | SAMSUNG SEMICONDUCTOR | CL31B106KAHNNNE |  | G |  |  |  |  |  |  |  |
|  |  |  |  |  | 45 | 62011HS00-023-G |  | CAP,10uF,+/-10%,X7R,25V,G,SMD1206 | TAIYO ELECTRIC IND.CO.LTD | TMK316B7106KL-TD |  | G |  |  |  |  |  |  |  |
|  |  |  |  | 46 | 46 | 620113A01-015-G | - | CAP,680pF,+/-5%,NPO,50V,G,SMD0402 | MURATA ELEC. NORTH AMERICA | GRM1555C1H681J | 2 | G | PECC42,PECC43 |  |  |  |  |  |  |
|  |  |  |  |  | 46 | 620113A00-012-G |  | CAP,680pF,+/-5%,NPO(C0G),50V,G,SMD0402 | WALSIN TECHNOLOGY CORPORATION | 0402N681J500LT |  | G |  |  |  |  |  |  |  |
|  |  |  |  |  | 46 | 620113A00-025-G |  | CAP,680pF,+/-5%,NPO(C0G),50V,G,SMD0402 | KEMET ELECTRONICS CORPORATION | C0402C681J5GAC |  | G |  |  |  |  |  |  |  |
|  |  |  |  |  | 46 | 620113A00-016-G |  | CAP,680pF,+/-5%,NPO(C0G),50V,G,SMD0402 | TDK ELECTRONICS EUROPE GMBH | C1005C0G1H681JT |  | G |  |  |  |  |  |  |  |
|  |  |  |  | 47 | 47 | 62012G200-015-G | - | CAP,22uF,+/-20%,X6S,4V,G,SMD0603 | MURATA ELEC. NORTH AMERICA | GRM188C80G226M | 12 | G | PECC44,PECC45,PECC46,PECC47,PECC48,PECC49,PECC50,PECC51,PECC52,PECC53,PECC54,PECC55 |  |  |  |  |  |  |
|  |  |  |  |  | 47 | 62012G200-012-G |  | CAP,22uF,+/-20%,X6S,4V,G,SMD0603 | WALSIN TECHNOLOGY CORPORATION | 0603S226M4R0CT |  | G |  |  |  |  |  |  |  |
|  |  |  |  |  | 47 | 62012G200-026-G |  | CAP,22uF,+/-20%,X6S,4V,G,SMD0603 | SAMSUNG SEMICONDUCTOR | CL10X226MR8NUNE |  | G |  |  |  |  |  |  |  |
|  |  |  |  |  | 47 | 62012G200-023-G |  | CAP,22uF,+/-20%,X6S,4V,G,SMD0603 | TAIYO ELECTRIC IND.CO.LTD | AMK107BC6226MA-T |  | G |  |  |  |  |  |  |  |
|  |  |  |  | 48 | 48 | 630330400-088-G | - | IND,150nH@100KHz,+/-10%,51A,304.5uOhm,SHLD,G,SMD | COOPER BUSSMANN, INC. | FP0906R1-R15-R | 2 | G | PECL1,PECL2 |  |  |  |  |  |  |
|  |  |  |  | 49 | 49 | 63033PG00-15A-G | - | IND,22nH@100KHz,+/-15%,22A,249.55uOhm,SHLD,G,SMD | The Inter-Technical Group, Inc. | SLC1615A-R022LHF | 1 | G | PECL3 |  |  |  |  |  |  |
|  |  |  |  | 50 | 50 | 61100LQ00-017-G |  | RES,20KOhm,+/-1%,1/16W,G,SMD0402 | KOA SPEER ELECTRONICS, INC. | RN731ETTP2002F50 | 1 | G | PECR1 |  |  |  |  |  |  |
|  |  |  |  |  | 50 | 61100LQ00-011-G |  | RES,20KOhm,+/-1%,1/16W,G,SMD0402 | YAGEO CORPORATION COMPONENT | RT0402FRE0720KL |  | G |  |  |  |  |  |  |  |
|  |  |  |  |  | 50 | 61100LQ00-044-G |  | RES,20KOhm,+/-1%,1/16W,G,SMD0402 | TA-I TECHNOLOGY CO., LTD. | RB04FTS2002 |  | G |  |  |  |  |  |  |  |
|  |  |  |  |  | 50 | 61100LQ00-012-G |  | RES,20KOhm,+/-1%,1/16W,G,SMD0402 | WALSIN TECHNOLOGY CORPORATION | WF04T2002FTL |  | G |  |  |  |  |  |  |  |
|  |  |  |  | 51 | 51 | 61011FP00-017-G |  | RES,113KOhm,+/-1%,1/16W,G,SMD0402 | KOA SPEER ELECTRONICS, INC. | RK73H1ETTP1133F | 2 | G | PECR2,PECR13 |  |  |  |  |  |  |
|  |  |  |  |  | 51 | 61011FP00-011-G |  | RES,113KOhm,+/-1%,1/16W,G,SMD0402 | YAGEO CORPORATION COMPONENT | RC0402FR-07113KL |  | G |  |  |  |  |  |  |  |
|  |  |  |  |  | 51 | 61011FP00-012-G |  | RES,113KOhm,+/-1%,1/16W,G,SMD0402 | WALSIN TECHNOLOGY CORPORATION | WR04X1133FTL |  | G |  |  |  |  |  |  |  |
|  |  |  |  |  | 51 | 61011FP00-044-G |  | RES,113KOhm,+/-1%,1/16W,G,SMD0402 | TA-I TECHNOLOGY CO., LTD. | RM04FTN1133 |  | G |  |  |  |  |  |  |  |
|  |  |  |  | 52 | 52 | 61011HP00-017-G |  | RES,44.2KOhm,+/-1%,1/16W,G,SMD0402 | KOA SPEER ELECTRONICS, INC. | RK73H1ETTP4422F | 1 | G | PECR3 |  |  |  |  |  |  |
|  |  |  |  |  | 52 | 61011HP00-012-G |  | RES,44.2KOhm,+/-1%,1/16W,G,SMD0402 | WALSIN TECHNOLOGY CORPORATION | WR04X4422FTL |  | G |  |  |  |  |  |  |  |
|  |  |  |  |  | 52 | 61011HP00-011-G |  | RES,44.2KOhm,+/-1%,1/16W,G,SMD0402 | YAGEO CORPORATION COMPONENT | RC0402FR-0744K2L |  | G |  |  |  |  |  |  |  |
|  |  |  |  |  | 52 | 61011HP00-044-G |  | RES,44.2KOhm,+/-1%,1/16W,G,SMD0402 | TA-I TECHNOLOGY CO., LTD. | RM04FTN4422 |  | G |  |  |  |  |  |  |  |
|  |  |  |  | 53 | 53 | 61011LH00-017-G |  | RES,9.31KOhm,+/-1%,1/16W,G,SMD0402 | KOA SPEER ELECTRONICS, INC. | RK73H1ETTP9311F | 1 | G | PECR4 |  |  |  |  |  |  |
|  |  |  |  |  | 53 | 61011LH00-011-G |  | RES,9.31KOhm,+/-1%,1/16W,G,SMD0402 | YAGEO CORPORATION COMPONENT | RC0402FR-079K31L |  | G |  |  |  |  |  |  |  |
|  |  |  |  |  | 53 | 61011LH00-012-G |  | RES,9.31KOhm,+/-1%,1/16W,G,SMD0402 | WALSIN TECHNOLOGY CORPORATION | WR04X9311FTL |  | G |  |  |  |  |  |  |  |
|  |  |  |  |  | 53 | 61011LH00-044-G |  | RES,9.31KOhm,+/-1%,1/16W,G,SMD0402 | TA-I TECHNOLOGY CO., LTD. | RM04FTN9311 |  | G |  |  |  |  |  |  |  |
|  |  |  |  | 54 | 54 | 61011H600-017-G |  | RES,16.5KOhm,+/-1%,1/16W,G,SMD0402 | KOA SPEER ELECTRONICS, INC. | RK73H1ETTP1652F | 1 | G | PECR5 |  |  |  |  |  |  |
|  |  |  |  |  | 54 | 61011H600-011-G |  | RES,16.5KOhm,+/-1%,1/16W,G,SMD0402 | YAGEO CORPORATION COMPONENT | RC0402FR-0716K5L |  | G |  |  |  |  |  |  |  |
|  |  |  |  |  | 54 | 61011H600-012-G |  | RES,16.5KOhm,+/-1%,1/16W,G,SMD0402 | WALSIN TECHNOLOGY CORPORATION | WR04X1652FTL |  | G |  |  |  |  |  |  |  |
|  |  |  |  | 55 | 55 | 610127Q00-017-G |  | RES,357KOhm,+/-1%,1/16W,G,SMD0402 | KOA SPEER ELECTRONICS, INC. | RK73H1ETTP3573F | 1 | G | PECR6 |  |  |  |  |  |  |
|  |  |  |  |  | 55 | 610127Q00-012-G |  | RES,357KOhm,+/-1%,1/16W,G,SMD0402 | WALSIN TECHNOLOGY CORPORATION | WR04X3573FTL |  | G |  |  |  |  |  |  |  |
|  |  |  |  |  | 55 | 610127Q00-011-G |  | RES,357KOhm,+/-1%,1/16W,G,SMD0402 | YAGEO CORPORATION COMPONENT | RC0402FR-07357KL |  | G |  |  |  |  |  |  |  |
|  |  |  |  |  | 55 | 610127Q00-044-G |  | RES,357KOhm,+/-1%,1/16W,G,SMD0402 | TA-I TECHNOLOGY CO., LTD. | RM04FTN3573 |  | G |  |  |  |  |  |  |  |
|  |  |  |  | 56 | 56 | 61011MG00-017-G |  | RES,42.2KOhm,+/-1%,1/16W,G,SMD0402 | KOA SPEER ELECTRONICS, INC. | RK73H1ETTP4222F | 1 | G | PECR7 |  |  |  |  |  |  |
|  |  |  |  |  | 56 | 61011MG00-012-G |  | RES,42.2KOhm,+/-1%,1/16W,G,SMD0402 | WALSIN TECHNOLOGY CORPORATION | WR04X4222FTL |  | G |  |  |  |  |  |  |  |
|  |  |  |  |  | 56 | 61011MG00-011-G |  | RES,42.2KOhm,+/-1%,1/16W,G,SMD0402 | YAGEO CORPORATION COMPONENT | RC0402FR-0742K2L |  | G |  |  |  |  |  |  |  |
|  |  |  |  |  | 56 | 61011MG00-044-G |  | RES,42.2KOhm,+/-1%,1/16W,G,SMD0402 | TA-I TECHNOLOGY CO., LTD. | RM04FTN4222 |  | G |  |  |  |  |  |  |  |
|  |  |  |  | 57 | 57 | 61011AQ00-017-G |  | RES,30.1KOhm,+/-1%,1/16W,G,SMD0402 | KOA SPEER ELECTRONICS, INC. | RK73H1ETTP3012F | 2 | G | PECR8,PECR12 |  |  |  |  |  |  |
|  |  |  |  |  | 57 | 61011AQ00-012-G |  | RES,30.1KOhm,+/-1%,1/16W,G,SMD0402 | WALSIN TECHNOLOGY CORPORATION | WR04X3012FTL |  | G |  |  |  |  |  |  |  |
|  |  |  |  |  | 57 | 61011AQ00-011-G |  | RES,30.1KOhm,+/-1%,1/16W,G,SMD0402 | YAGEO CORPORATION COMPONENT | RC0402FR-0730K1L |  | G |  |  |  |  |  |  |  |
|  |  |  |  |  | 57 | 61011AQ00-044-G |  | RES,30.1KOhm,+/-1%,1/16W,G,SMD0402 | TA-I TECHNOLOGY CO., LTD. | RM04FTN3012 |  | G |  |  |  |  |  |  |  |
|  |  |  |  | 58 | 58 | 61100K600-017-G |  | RES,24KOhm,+/-0.1%,1/16W,G,SMD0402 | KOA SPEER ELECTRONICS, INC. | RN731ETTP2402B25 | 1 | G | PECR9 |  |  |  |  |  |  |
|  |  |  |  | 59 | 59 | 610116G00-017-G | - | RES,150KOhm,+/-1%,1/16W,G,SMD0402 | KOA SPEER ELECTRONICS, INC. | RK73H1ETTP1503F | 1 | G | PECR10 |  |  |  |  |  |  |
|  |  |  |  |  | 59 | 610116G00-011-G |  | RES,150KOhm,+/-1%,1/16W,G,SMD0402 | YAGEO CORPORATION COMPONENT | RC0402FR-07150KL |  | G |  |  |  |  |  |  |  |
|  |  |  |  |  | 59 | 610116G00-012-G |  | RES,150KOhm,+/-1%,1/16W,G,SMD0402 | WALSIN TECHNOLOGY CORPORATION | WR04X1503FTL |  | G |  |  |  |  |  |  |  |
|  |  |  |  |  | 59 | 610116G00-044-G |  | RES,150KOhm,+/-1%,1/16W,G,SMD0402 | TA-I TECHNOLOGY CO., LTD. | RM04FTN1503 |  | G |  |  |  |  |  |  |  |
|  |  |  |  | 60 | 60 | 610114H00-017-G | - | RES,20KOhm,+/-1%,1/16W,G,SMD0402 | KOA SPEER ELECTRONICS, INC. | RK73H1ETTP2002F | 2 | G | PELR10,PECR11 |  |  |  |  |  |  |
|  |  |  |  |  | 60 | 610114H00-011-G |  | RES,20KOhm,+/-1%,1/16W,G,SMD0402 | YAGEO CORPORATION COMPONENT | RC0402FR-0720KL |  | G |  |  |  |  |  |  |  |
|  |  |  |  |  | 60 | 610114H00-012-G |  | RES,20KOhm,+/-1%,1/16W,G,SMD0402 | WALSIN TECHNOLOGY CORPORATION | WR04X2002FTL |  | G |  |  |  |  |  |  |  |
|  |  |  |  |  | 60 | 610114H00-044-G |  | RES,20KOhm,+/-1%,1/16W,G,SMD0402 | TA-I TECHNOLOGY CO., LTD. | RM04FTN2002 |  | G |  |  |  |  |  |  |  |
|  |  |  |  |  | 60 | 610114H00-024-G |  | RES,20KOhm,+/-1%,1/16W,G,SMD0402 | PANASONIC INDUSTRIAL CO.,LTD. | ERJ2RKF2002x |  | G |  |  |  |  |  |  |  |
|  |  |  |  |  | 60 | 610114H00-030-G |  | RES,20KOhm,+/-1%,1/16W,G,SMD0402 | ROHM CORPORATION | MCR01MZPF2002 |  | G |  |  |  |  |  |  |  |
|  |  |  |  |  | 60 | 610114H04-029-G |  | RES,20KOhm,+/-1%,1/16W,G,SMD0402 | VISHAY ENTER TECHNO LOGY.INC | CRCW040220K0FKEDC |  | G |  |  |  |  |  |  |  |
|  |  |  |  | 61 | 61 | 61011TN00-017-G |  | RES,39KOhm,+/-1%,1/16W,G,SMD0402 | KOA SPEER ELECTRONICS, INC. | RK73H1ETTP3902F | 1 | G | PECR14 |  |  |  |  |  |  |
|  |  |  |  |  | 61 | 61011TN00-011-G |  | RES,39KOhm,+/-1%,1/16W,G,SMD0402 | YAGEO CORPORATION COMPONENT | RC0402FR-0739KL |  | G |  |  |  |  |  |  |  |
|  |  |  |  |  | 61 | 61011TN00-012-G |  | RES,39KOhm,+/-1%,1/16W,G,SMD0402 | WALSIN TECHNOLOGY CORPORATION | WR04X3902FTL |  | G |  |  |  |  |  |  |  |
|  |  |  |  |  | 61 | 61011TN00-044-G |  | RES,39KOhm,+/-1%,1/16W,G,SMD0402 | TA-I TECHNOLOGY CO., LTD. | RM04FTN3902 |  | G |  |  |  |  |  |  |  |
|  |  |  |  | 62 | 62 | 61010L300-017-G | - | RES,1KOhm,+/-1%,1/16W,G,SMD0402 | KOA SPEER ELECTRONICS, INC. | RK73H1ETTP1001F | 24 | G | PECR16,PECR25,R206,R207,R216,R217,R226,R227,R378,R379,R380,R387,R388,R389,R390,R403,R433,R434,R435,R438,R1401,R1402,R1537,R1538 |  |  |  |  |  |  |
|  |  |  |  |  | 62 | 61010L300-012-G |  | RES,1KOhm,+/-1%,1/16W,G,SMD0402 | WALSIN TECHNOLOGY CORPORATION | WR04X1001FTL |  | G |  |  |  |  |  |  |  |
|  |  |  |  |  | 62 | 61010L300-011-G |  | RES,1KOhm,+/-1%,1/16W,G,SMD0402 | YAGEO CORPORATION COMPONENT | RC0402FR-071KL |  | G |  |  |  |  |  |  |  |
|  |  |  |  |  | 62 | 61010L300-044-G |  | RES,1KOhm,+/-1%,1/16W,G,SMD0402 | TA-I TECHNOLOGY CO., LTD. | RM04FTN1001 |  | G |  |  |  |  |  |  |  |
|  |  |  |  |  | 62 | 61010L300-024-G |  | RES,1KOhm,+/-1%,1/16W,G,SMD0402 | PANASONIC INDUSTRIAL CO.,LTD. | ERJ2RKF1001X |  | G |  |  |  |  |  |  |  |
|  |  |  |  |  | 62 | 61010L300-029-G |  | RES,1KOhm,+/-1%,1/16W,G,SMD0402 | VISHAY ENTER TECHNO LOGY.INC | CRCW04021K00FKED |  | G |  |  |  |  |  |  |  |
|  |  |  |  | 63 | 63 | 610107A00-017-G | - | RES,0 Ohm,+/-5%,1/16W,G,SMD0402 | KOA SPEER ELECTRONICS, INC. | RK73Z1ETTP | 79 | G | PLTR1,PSLR2,PSGR2,PSCR2,PFCR2,PELR2,PFCR3,PSCR7,PELR7,PSRR8,PSCR8,PSRR9,PSLR9,PSGR9,PFCR9,PELR9,R11,PFCR11,PSLR13,PSCR14,PSRR15,PSLR15,PSGR15,PELR15,PELR16,PFCR17,PELR17,PSRR18,PSLR18,PSGR18,PFCR18,PSCR22,PECR22,PECR23,PECR28,PECR30,PECR37,PECR38,PECR41,PECR42,PECR44,PECR52,PECR53,R131,R132,R133,R135,R137,R189,R198,R204,R205,R212,R213,R214,R215,R220,R221,R222,R223,R237,R250,R1387,R1388,R1410,R1441,R1445,R1513,R1514,R1515,R1516,R1520,R1524,R1535,R1536,R1540,PSCR3001,PSCR3002,PSCR3003 |  |  |  |  |  |  |
|  |  |  |  |  | 63 | 610107A00-012-G |  | RES,0 Ohm,+/-5%,1/16W,G,SMD0402 | WALSIN TECHNOLOGY CORPORATION | WR04X000PTL |  | G |  |  |  |  |  |  |  |
|  |  |  |  |  | 63 | 610107A00-011-G |  | RES,0 Ohm,+/-5%,1/16W,G,SMD0402 | YAGEO CORPORATION COMPONENT | RC0402JR-070RL |  | G |  |  |  |  |  |  |  |
|  |  |  |  |  | 63 | 610107A00-044-G |  | RES,0 Ohm,+/-5%,1/16W,G,SMD0402 | TA-I TECHNOLOGY CO., LTD. | RM04JTN0 |  | G |  |  |  |  |  |  |  |
|  |  |  |  |  | 63 | 610107A00-024-G |  | RES,0 Ohm,+/-5%,1/16W,G,SMD0402 | PANASONIC INDUSTRIAL CO.,LTD. | ERJ2GE0R00X |  | G |  |  |  |  |  |  |  |
|  |  |  |  |  | 63 | 610107A00-029-G |  | RES,0 Ohm,+/-5%,1/16W,G,SMD0402 | VISHAY ENTER TECHNO LOGY.INC | CRCW04020000Z0ED |  | G |  |  |  |  |  |  |  |
|  |  |  |  | 64 | 64 | 61010LE00-017-G |  | RES,12KOhm,+/-1%,1/16W,G,SMD0402 | KOA SPEER ELECTRONICS, INC. | RK73H1ETTP1202F | 1 | G | PECR24 |  |  |  |  |  |  |
|  |  |  |  |  | 64 | 61010LE00-011-G |  | RES,12KOhm,+/-1%,1/16W,G,SMD0402 | YAGEO CORPORATION COMPONENT | RC0402FR-0712KL |  | G |  |  |  |  |  |  |  |
|  |  |  |  |  | 64 | 61010LE00-012-G |  | RES,12KOhm,+/-1%,1/16W,G,SMD0402 | WALSIN TECHNOLOGY CORPORATION | WR04X1202FTL |  | G |  |  |  |  |  |  |  |
|  |  |  |  |  | 64 | 61010LE00-044-G |  | RES,12KOhm,+/-1%,1/16W,G,SMD0402 | TA-I TECHNOLOGY CO., LTD. | RM04FTN1202 |  | G |  |  |  |  |  |  |  |
|  |  |  |  | 65 | 65 | 610114S00-017-G | - | RES,4.99KOhm,+/-1%,1/16W,G,SMD0402 | KOA SPEER ELECTRONICS, INC. | RK73H1ETTP4991F | 3 | G | PSRR3,PSCR9,PECR26 |  |  |  |  |  |  |
|  |  |  |  |  | 65 | 610114S00-012-G |  | RES,4.99KOhm,+/-1%,1/16W,G,SMD0402 | WALSIN TECHNOLOGY CORPORATION | WR04X4991FTL |  | G |  |  |  |  |  |  |  |
|  |  |  |  |  | 65 | 610114S00-011-G |  | RES,4.99KOhm,+/-1%,1/16W,G,SMD0402 | YAGEO CORPORATION COMPONENT | RC0402FR-074K99L |  | G |  |  |  |  |  |  |  |
|  |  |  |  |  | 65 | 610114S00-044-G |  | RES,4.99KOhm,+/-1%,1/16W,G,SMD0402 | TA-I TECHNOLOGY CO., LTD. | RM04FTN4991 |  | G |  |  |  |  |  |  |  |
|  |  |  |  |  | 65 | 610114S00-024-G |  | RES,4.99KOhm,+/-1%,1/16W,G,SMD0402 | PANASONIC INDUSTRIAL CO.,LTD. | ERJ2RKF4991X |  | G |  |  |  |  |  |  |  |
|  |  |  |  | 66 | 66 | 61011GY00-017-G | - | RES,2.43KOhm,+/-1%,1/16W,G,SMD0402 | KOA SPEER ELECTRONICS, INC. | RK73H1ETTP2431F | 1 | G | PECR27 |  |  |  |  |  |  |
|  |  |  |  |  | 66 | 61011GY00-012-G |  | RES,2.43KOhm,+/-1%,1/16W,G,SMD0402 | WALSIN TECHNOLOGY CORPORATION | WR04X2431FTL |  | G |  |  |  |  |  |  |  |
|  |  |  |  |  | 66 | 61011GY00-011-G |  | RES,2.43KOhm,+/-1%,1/16W,G,SMD0402 | YAGEO CORPORATION COMPONENT | RC0402FR-072K43L |  | G |  |  |  |  |  |  |  |
|  |  |  |  |  | 66 | 61011GY00-044-G |  | RES,2.43KOhm,+/-1%,1/16W,G,SMD0402 | TA-I TECHNOLOGY CO., LTD. | RM04FTN2431 |  | G |  |  |  |  |  |  |  |
|  |  |  |  | 67 | 67 | 61011C300-017-G |  | RES,2.2 Ohm,+/-1%,1/16W,G,SMD0402 | KOA SPEER ELECTRONICS, INC. | RK73H1ETTP2R20F | 1 | G | PECR29 |  |  |  |  |  |  |
|  |  |  |  |  | 67 | 61011C300-012-G |  | RES,2.2 Ohm,+/-1%,1/16W,G,SMD0402 | WALSIN TECHNOLOGY CORPORATION | WR04W2R20FTL |  | G |  |  |  |  |  |  |  |
|  |  |  |  |  | 67 | 61011C300-011-G |  | RES,2.2 Ohm,+/-1%,1/16W,G,SMD0402 | YAGEO CORPORATION COMPONENT | RC0402FR-072R2L |  | G |  |  |  |  |  |  |  |
|  |  |  |  |  | 67 | 61011C300-044-G |  | RES,2.2 Ohm,+/-1%,1/16W,G,SMD0402 | TA-I TECHNOLOGY CO., LTD. | RM04FTN2R20 |  | G |  |  |  |  |  |  |  |
|  |  |  |  | 68 | 68 | 610108300-017-G | - | RES,0 Ohm,+/-5%,1/10W,G,SMD0603 | KOA SPEER ELECTRONICS, INC. | RK73Z1JTTD | 2 | G | PECR31,PECR32 |  |  |  |  |  |  |
|  |  |  |  |  | 68 | 610108300-012-G |  | RES,0 Ohm,+/-5%,1/10W,G,SMD0603 | WALSIN TECHNOLOGY CORPORATION | WR06X000PTL |  | G |  |  |  |  |  |  |  |
|  |  |  |  |  | 68 | 610108300-011-G |  | RES,0 Ohm,+/-5%,1/10W,G,SMD0603 | YAGEO CORPORATION COMPONENT | RC0603JR-070RL |  | G |  |  |  |  |  |  |  |
|  |  |  |  |  | 68 | 610108300-044-G |  | RES,0 Ohm,+/-5%,1/10W,G,SMD0603 | TA-I TECHNOLOGY CO., LTD. | RM06JTN0 |  | G |  |  |  |  |  |  |  |
|  |  |  |  |  | 68 | 610108300-024-G |  | RES,0 Ohm,+/-5%,1/10W,G,SMD0603 | PANASONIC INDUSTRIAL CO.,LTD. | ERJ3GEY0R00V |  | G |  |  |  |  |  |  |  |
|  |  |  |  | 69 | 69 | 610113800-017-G | - | RES,10 Ohm,+/-1%,1/16W,G,SMD0402 | KOA SPEER ELECTRONICS, INC. | RK73H1ETTP10R0F | 13 | G | PFCR4,PECR33,PECR34,R105,R106,R107,R108,R109,R110,R111,R112,R113,R114 |  |  |  |  |  |  |
|  |  |  |  |  | 69 | 610113800-012-G |  | RES,10 Ohm,+/-1%,1/16W,G,SMD0402 | WALSIN TECHNOLOGY CORPORATION | WR04X10R0FTL |  | G |  |  |  |  |  |  |  |
|  |  |  |  |  | 69 | 610113800-011-G |  | RES,10 Ohm,+/-1%,1/16W,G,SMD0402 | YAGEO CORPORATION COMPONENT | RC0402FR-0710RL |  | G |  |  |  |  |  |  |  |
|  |  |  |  |  | 69 | 610113800-044-G |  | RES,10 Ohm,+/-1%,1/16W,G,SMD0402 | TA-I TECHNOLOGY CO., LTD. | RM04FTN10R0 |  | G |  |  |  |  |  |  |  |
|  |  |  |  | 70 | 70 | 61011HA00-017-G |  | RES,1 Ohm,+/-1%,1/16W,G,SMD0402 | KOA SPEER ELECTRONICS, INC. | RK73H1ETTP1R00F | 7 | G | PSCR4,PSRR5,PSLR5,PSGR5,PFCR7,PECR39,PECR40 |  |  |  |  |  |  |
|  |  |  |  |  | 70 | 61011HA00-012-G |  | RES,1 Ohm,+/-1%,1/16W,G,SMD0402 | WALSIN TECHNOLOGY CORPORATION | WR04W1R00FTL |  | G |  |  |  |  |  |  |  |
|  |  |  |  |  | 70 | 61011HA00-011-G |  | RES,1 Ohm,+/-1%,1/16W,G,SMD0402 | YAGEO CORPORATION COMPONENT | RC0402FR-071RL |  | G |  |  |  |  |  |  |  |
|  |  |  |  |  | 70 | 61011HA00-044-G |  | RES,1 Ohm,+/-1%,1/16W,G,SMD0402 | TA-I TECHNOLOGY CO., LTD. | RM04FTN1R00 |  | G |  |  |  |  |  |  |  |
|  |  |  |  |  | 70 | 61011HA00-029-G |  | RES,1 Ohm,+/-1%,1/16W,G,SMD0402 | VISHAY ENTER TECHNO LOGY.INC | CRCW04021R00FNED |  | G |  |  |  |  |  |  |  |
|  |  |  |  | 71 | 71 | 61010FE00-017-G | - | RES,100 Ohm,+/-1%,1/16W,G,SMD0402 | KOA SPEER ELECTRONICS, INC. | RK73H1ETTP1000F | 30 | G | PECR43,R73,R74,R96,R1380,R1449,R1450,R1455,R1456,R1457,R1458,R1459,R1460,R1461,R1462,R1463,R1464,R1465,R1466,R1467,R1468,R1469,R1470,R1471,R1472,R1473,R1474,R1475,R1476,R1477 |  |  |  |  |  |  |
|  |  |  |  |  | 71 | 61010FE00-012-G |  | RES,100 Ohm,+/-1%,1/16W,G,SMD0402 | WALSIN TECHNOLOGY CORPORATION | WR04X1000FTL |  | G |  |  |  |  |  |  |  |
|  |  |  |  |  | 71 | 61010FE00-011-G |  | RES,100 Ohm,+/-1%,1/16W,G,SMD0402 | YAGEO CORPORATION COMPONENT | RC0402FR-07100RL |  | G |  |  |  |  |  |  |  |
|  |  |  |  |  | 71 | 61010FE00-044-G |  | RES,100 Ohm,+/-1%,1/16W,G,SMD0402 | TA-I TECHNOLOGY CO., LTD. | RM04FTN1000 |  | G |  |  |  |  |  |  |  |
|  |  |  |  | 72 | 72 | 610125N00-017-G |  | RES,3.3 Ohm,+/-1%,1/16W,G,SMD0402 | KOA SPEER ELECTRONICS, INC. | RK73H1ETTP3R30F | 2 | G | PECR45,PECR46 |  |  |  |  |  |  |
|  |  |  |  |  | 72 | 610125N00-012-G |  | RES,3.3 Ohm,+/-1%,1/16W,G,SMD0402 | WALSIN TECHNOLOGY CORPORATION | WR04W3R30FTL |  | G |  |  |  |  |  |  |  |
|  |  |  |  |  | 72 | 610125N00-011-G |  | RES,3.3 Ohm,+/-1%,1/16W,G,SMD0402 | YAGEO CORPORATION COMPONENT | RC0402FR-073R3L |  | G |  |  |  |  |  |  |  |
|  |  |  |  |  | 72 | 610125N00-044-G |  | RES,3.3 Ohm,+/-1%,1/16W,G,SMD0402 | TA-I TECHNOLOGY CO., LTD. | RM04FTN3R30 |  | G |  |  |  |  |  |  |  |
|  |  |  |  | 73 | 73 | 610101100-017-G |  | RES,1 Ohm,+/-1%,1/10W,G,SMD0603 | KOA SPEER ELECTRONICS, INC. | RK73H1JTTD1R00F | 9 | G | PELR4,PELR11,PELR13,PFCR14,PFCR16,PECR47,PECR48,PECR49,PECR50 |  |  |  |  |  |  |
|  |  |  |  |  | 73 | 610101100-011-G |  | RES,1 Ohm,+/-1%,1/10W,G,SMD0603 | YAGEO CORPORATION COMPONENT | RC0603FR-071RL |  | G |  |  |  |  |  |  |  |
|  |  |  |  |  | 73 | 610101100-012-G |  | RES,1 Ohm,+/-1%,1/10W,G,SMD0603 | WALSIN TECHNOLOGY CORPORATION | WR06W1R00FTL |  | G |  |  |  |  |  |  |  |
|  |  |  |  |  | 73 | 610101100-044-G |  | RES,1 Ohm,+/-1%,1/10W,G,SMD0603 | TA-I TECHNOLOGY CO., LTD. | RM06FTN1R00 |  | G |  |  |  |  |  |  |  |
|  |  |  |  | 74 | 74 | 32022VJ00-183-G |  | IC,PWM Controller,TPS53641RSBR,G,QFN-40,SMD | TEXAS INSTRUMENTS | TPS53641RSBR | 1 | G | PECU1 |  |  |  |  |  |  |
|  |  |  |  | 75 | 75 | 320240000-183-G |  | IC,PWM Controller,CSD95472Q5MC,G,SON-13,SMD | TEXAS INSTRUMENTS | CSD95472Q5MC | 2 | G | PECU2,PECU3 |  |  |  |  |  |  |
|  |  |  |  | 76 | 76 | 62012PT00-015-G | - | CAP,22uF,+/-20%,X6S,16V,G,SMD0805 | MURATA ELEC. NORTH AMERICA | GRM21BC81C226M | 15 | G | PSRC7,PLTC7,PSRC8,PLTC8,PLTC9,PLTC10,PSRC11,PSRC12,PELC12,PELC13,PELC14,PSRC15,PELC15,PELC18,PELC19 |  |  |  |  |  |  |
|  |  |  |  |  | 76 | 62012PT00-023-G |  | CAP,22uF,+/-20%,X6S,16V,G,SMD0805 | TAIYO ELECTRIC IND.CO.LTD | EDK212BC6226MG-T |  | G |  |  |  |  |  |  |  |
|  |  |  |  | 77 | 77 | 62011G000-015-G | - | CAP,1uF,+/-10%,X5R,16V,G,SMD0402 | MURATA ELEC. NORTH AMERICA | GRM155R61C105K | 1 | G | PELC16 |  |  |  |  |  |  |
|  |  |  |  |  | 77 | 62011G000-026-G |  | CAP,1uF,+/-10%,X5R,16V,G,SMD0402 | SAMSUNG SEMICONDUCTOR | CL05A105KO5NNNC |  | G |  |  |  |  |  |  |  |
|  |  |  |  |  | 77 | 62011G000-023-G |  | CAP,1uF,+/-10%,X5R,16V,G,SMD0402 | TAIYO ELECTRIC IND.CO.LTD | EMK105BJ105KV-F |  | G |  |  |  |  |  |  |  |
|  |  |  |  |  | 77 | 62011G000-012-G |  | CAP,1uF,+/-10%,X5R,16V,G,SMD0402 | WALSIN TECHNOLOGY CORPORATION | 0402X105K160CT |  | G |  |  |  |  |  |  |  |
|  |  |  |  | 78 | 78 | 72010RE00-015-G |  | FB,26 Ohm@100MHz,+/-25%,6A,7mOhm,G,SMD0603 | MURATA ELEC. NORTH AMERICA | BLM18KG260TN1D | 8 | G | PSRL1,PSLL1,PSGL1,PLTL1,PFCL1,PELL1,PELL3,PELL4 |  |  |  |  |  |  |
|  |  |  |  | 79 | 79 | 63033RJ00-15A-G |  | IND,4.7uH@100KHz,+/-20%,3.5A,65mOhm,SHLD,G,SMD | The Inter-Technical Group, Inc. | SMHC2011-4R7MHF | 1 | G | PELL2 |  |  |  |  |  |  |
|  |  |  |  | 80 | 80 | 611003200-017-G |  | RES,10KOhm,+/-0.1%,1/16W,G,SMD0402 | KOA SPEER ELECTRONICS, INC. | RN731ETTP1002B25 | 2 | G | PELR3,PFCR5 |  |  |  |  |  |  |
|  |  |  |  | 81 | 81 | 61100UT00-017-G |  | RES,20.5KOhm,+/-0.1%,1/16W,G,SMD0402 | KOA SPEER ELECTRONICS, INC. | RN731ETTP2052B25 | 1 | G | PELR5 |  |  |  |  |  |  |
|  |  |  |  | 82 | 82 | 61010LA00-017-G | - | RES,4.7KOhm,+/-1%,1/16W,G,SMD0402 | KOA SPEER ELECTRONICS, INC. | RK73H1ETTP4701F | 8 | G | PSCR1,PELR6,PFCR8,R229,R230,R251,R252,R1539 |  |  |  |  |  |  |
|  |  |  |  |  | 82 | 61010LA00-012-G |  | RES,4.7KOhm,+/-1%,1/16W,G,SMD0402 | WALSIN TECHNOLOGY CORPORATION | WR04X4701FTL |  | G |  |  |  |  |  |  |  |
|  |  |  |  |  | 82 | 61010LA00-011-G |  | RES,4.7KOhm,+/-1%,1/16W,G,SMD0402 | YAGEO CORPORATION COMPONENT | RC0402FR-074K7L |  | G |  |  |  |  |  |  |  |
|  |  |  |  |  | 82 | 61010LA00-044-G |  | RES,4.7KOhm,+/-1%,1/16W,G,SMD0402 | TA-I TECHNOLOGY CO., LTD. | RM04FTN4701 |  | G |  |  |  |  |  |  |  |
|  |  |  |  | 83 | 83 | 61011UM00-017-G | - | RES,240KOhm,+/-1%,1/16W,G,SMD0402 | KOA SPEER ELECTRONICS, INC. | RK73H1ETTP2403F | 2 | G | PELR12,PFCR13 |  |  |  |  |  |  |
|  |  |  |  |  | 83 | 61011UM00-011-G |  | RES,240KOhm,+/-1%,1/16W,G,SMD0402 | YAGEO CORPORATION COMPONENT | RC0402FR-07240KL |  | G |  |  |  |  |  |  |  |
|  |  |  |  |  | 83 | 61011UM00-012-G |  | RES,240KOhm,+/-1%,1/16W,G,SMD0402 | WALSIN TECHNOLOGY CORPORATION | WR04X2403FTL |  | G |  |  |  |  |  |  |  |
|  |  |  |  |  | 83 | 61011UM00-044-G |  | RES,240KOhm,+/-1%,1/16W,G,SMD0402 | TA-I TECHNOLOGY CO., LTD. | RM04FTN2403 |  | G |  |  |  |  |  |  |  |
|  |  |  |  | 84 | 84 | 61011YJ00-017-G |  | RES,71.5KOhm,+/-1%,1/16W,G,SMD0402 | KOA SPEER ELECTRONICS, INC. | RK73H1ETTP7152F | 2 | G | PELR14,PFCR15 |  |  |  |  |  |  |
|  |  |  |  |  | 84 | 61011YJ00-011-G |  | RES,71.5KOhm,+/-1%,1/16W,G,SMD0402 | YAGEO CORPORATION COMPONENT | RC0402FR-0771K5L |  | G |  |  |  |  |  |  |  |
|  |  |  |  |  | 84 | 61011YJ00-012-G |  | RES,71.5KOhm,+/-1%,1/16W,G,SMD0402 | WALSIN TECHNOLOGY CORPORATION | WR04X7152FTL |  | G |  |  |  |  |  |  |  |
|  |  |  |  |  | 84 | 61011YJ00-044-G |  | RES,71.5KOhm,+/-1%,1/16W,G,SMD0402 | TA-I TECHNOLOGY CO., LTD. | RM04FTN7152 |  | G |  |  |  |  |  |  |  |
|  |  |  |  | 85 | 85 | 32013BY00-183-G |  | IC,Regulator,TPS53513RVER,8A,ADJ,G,QFN-28,SMD | TEXAS INSTRUMENTS | TPS53513RVER | 1 | G | PELU1 |  |  |  |  |  |  |
|  |  |  |  | 86 | 86 | 63033JL00-15A-G |  | IND,470nH@100KHz,+/-20%,13.5A,4.2mOhm,SHLD,G,SMD | The Inter-Technical Group, Inc. | SMHC2511-R47MHF | 1 | G | PFCL2 |  |  |  |  |  |  |
|  |  |  |  | 87 | 87 | 610116N00-017-G |  | RES,5.1KOhm,+/-1%,1/16W,G,SMD0402 | KOA SPEER ELECTRONICS, INC. | RK73H1ETTP5101F | 1 | G | PFCR6 |  |  |  |  |  |  |
|  |  |  |  |  | 87 | 610116N00-011-G |  | RES,5.1KOhm,+/-1%,1/16W,G,SMD0402 | YAGEO CORPORATION COMPONENT | RC0402FR-075K1L |  | G |  |  |  |  |  |  |  |
|  |  |  |  |  | 87 | 610116N00-012-G |  | RES,5.1KOhm,+/-1%,1/16W,G,SMD0402 | WALSIN TECHNOLOGY CORPORATION | WR04X5101FTL |  | G |  |  |  |  |  |  |  |
|  |  |  |  |  | 87 | 610116N00-044-G |  | RES,5.1KOhm,+/-1%,1/16W,G,SMD0402 | TA-I TECHNOLOGY CO., LTD. | RM04FTN5101 |  | G |  |  |  |  |  |  |  |
|  |  |  |  | 88 | 88 | 61011VM00-017-G | - | RES,57.6KOhm,+/-1%,1/16W,G,SMD0402 | KOA SPEER ELECTRONICS, INC. | RK73H1ETTP5762F | 1 | G | PFCR12 |  |  |  |  |  |  |
|  |  |  |  |  | 88 | 61011VM00-011-G |  | RES,57.6KOhm,+/-1%,1/16W,G,SMD0402 | YAGEO CORPORATION COMPONENT | RC0402FR-0757K6L |  | G |  |  |  |  |  |  |  |
|  |  |  |  |  | 88 | 61011VM00-012-G |  | RES,57.6KOhm,+/-1%,1/16W,G,SMD0402 | WALSIN TECHNOLOGY CORPORATION | WR04X5762FTL |  | G |  |  |  |  |  |  |  |
|  |  |  |  |  | 88 | 61011VM00-044-G |  | RES,57.6KOhm,+/-1%,1/16W,G,SMD0402 | TA-I TECHNOLOGY CO., LTD. | RM04FTN5762 |  | G |  |  |  |  |  |  |  |
|  |  |  |  | 89 | 89 | 320143Y00-183-G | - | IC,Regulator,TPS548A20RVER,ADJ,15A,G,VQFN-28,SMD | TEXAS INSTRUMENTS | TPS548A20RVER | 1 | G | PFCU1 |  |  |  |  |  |  |
|  |  |  |  | 90 | 90 | 62012T500-015-G |  | CAP,22uF,+/-20%,X7S,25V,G,SMD1206 | MURATA ELEC. NORTH AMERICA | GRM31CC71E226ME11L | 18 | G | PSRC2,PSLC2,PSGC2,PLTC2,PLTC3,PSCC6,PSCC7,PSCC8,PSCC9,PSRC17,PSLC17,PSGC17,PSRC18,PSLC18,PSGC18,PSRC19,PSCC3005,PSCC3009 |  |  |  |  |  |  |
|  |  |  |  | 91 | 91 | 61011FG00-017-G |  | RES,107KOhm,+/-1%,1/16W,G,SMD0402 | KOA SPEER ELECTRONICS, INC. | RK73H1ETTP1073F | 1 | G | PLTR2 |  |  |  |  |  |  |
|  |  |  |  |  | 91 | 61011FG00-012-G |  | RES,107KOhm,+/-1%,1/16W,G,SMD0402 | WALSIN TECHNOLOGY CORPORATION | WR04X1073FTL |  | G |  |  |  |  |  |  |  |
|  |  |  |  |  | 91 | 61011FG00-011-G |  | RES,107KOhm,+/-1%,1/16W,G,SMD0402 | YAGEO CORPORATION COMPONENT | RC0402FR-07107KL |  | G |  |  |  |  |  |  |  |
|  |  |  |  |  | 91 | 61011FG00-044-G |  | RES,107KOhm,+/-1%,1/16W,G,SMD0402 | TA-I TECHNOLOGY CO., LTD. | RM04FTN1073 |  | G |  |  |  |  |  |  |  |
|  |  |  |  | 92 | 92 | 610118700-017-G |  | RES,51.1KOhm,+/-1%,1/16W,G,SMD0402 | KOA SPEER ELECTRONICS, INC. | RK73H1ETTP5112F | 1 | G | PLTR3 |  |  |  |  |  |  |
|  |  |  |  |  | 92 | 610118700-012-G |  | RES,51.1KOhm,+/-1%,1/16W,G,SMD0402 | WALSIN TECHNOLOGY CORPORATION | WR04X5112FTL |  | G |  |  |  |  |  |  |  |
|  |  |  |  |  | 92 | 610118700-011-G |  | RES,51.1KOhm,+/-1%,1/16W,G,SMD0402 | YAGEO CORPORATION COMPONENT | RC0402FR-0751K1L |  | G |  |  |  |  |  |  |  |
|  |  |  |  |  | 92 | 610118700-044-G |  | RES,51.1KOhm,+/-1%,1/16W,G,SMD0402 | TA-I TECHNOLOGY CO., LTD. | RM04FTN5112 |  | G |  |  |  |  |  |  |  |
|  |  |  |  | 93 | 93 | 611004M00-017-G |  | RES,16.5KOhm,+/-0.1%,1/16W,G,SMD0402 | KOA SPEER ELECTRONICS, INC. | RN731ETTP1652B25 | 3 | G | PLTR4,PSRR17,PSLR17 |  |  |  |  |  |  |
|  |  |  |  | 94 | 94 | 610119P00-017-G | - | RES,5.11KOhm,+/-1%,1/16W,G,SMD0402 | KOA SPEER ELECTRONICS, INC. | RK73H1ETTP5111F | 1 | G | PLTR5 |  |  |  |  |  |  |
|  |  |  |  |  | 94 | 610119P00-012-G |  | RES,5.11KOhm,+/-1%,1/16W,G,SMD0402 | WALSIN TECHNOLOGY CORPORATION | WR04X5111FTL |  | G |  |  |  |  |  |  |  |
|  |  |  |  |  | 94 | 610119P00-011-G |  | RES,5.11KOhm,+/-1%,1/16W,G,SMD0402 | YAGEO CORPORATION COMPONENT | RC0402FR-075K11L |  | G |  |  |  |  |  |  |  |
|  |  |  |  |  | 94 | 610119P00-024-G |  | RES,5.11KOhm,+/-1%,1/16W,G,SMD0402 | PANASONIC INDUSTRIAL CO.,LTD. | ERJ2RKF5111X |  | G |  |  |  |  |  |  |  |
|  |  |  |  |  | 94 | 610119P00-029-G |  | RES,5.11KOhm,+/-1%,1/16W,G,SMD0402 | VISHAY ENTER TECHNO LOGY.INC | CRCW04025K11FKED |  | G |  |  |  |  |  |  |  |
|  |  |  |  | 95 | 95 | 320128V00-183-G |  | IC,Regulator,TPS73801DCQR,1A,ADJ,G,SOT223-5,SMD | TEXAS INSTRUMENTS | TPS73801DCQR | 1 | G | PLTU1 |  |  |  |  |  |  |
|  |  |  |  | 96 | 96 | 62120CM00-024-G | - | SPEA CAP,220uF,+10%~-35%,6.3V,105C,G,SMD2816,ESR<=15mOhm | PANASONIC INDUSTRIAL CO.,LTD. | EEFCX0J221YR | 2 | G | PSCCE3003,PSCCE3004 |  |  |  |  |  |  |
|  |  |  |  | 97 | 97 | 62012GF00-015-G | - | CAP,22uF,+/-20%,X6S,6.3V,G,SMD0603 | MURATA ELEC. NORTH AMERICA | GRM188C80J226M | 6 | G | PSCC2,PSCC3,PSCC3000,PSCC3010,PSCC3011,PSCC3012 |  |  |  |  |  |  |
|  |  |  |  |  | 97 | 62012GF00-023-G |  | CAP,22uF,+/-20%,X6S,6.3V,G,SMD0603 | TAIYO ELECTRIC IND.CO.LTD | JDK107BC6226MA-T |  | G |  |  |  |  |  |  |  |
|  |  |  |  | 98 | 98 | 620108000-015-G | - | CAP,100pF,+/-5%,NPO(C0G),50V,G,SMD0402 | MURATA ELEC. NORTH AMERICA | GRM1555C1H101J | 3 | G | PSCC4,PSLC14,PSGC14 |  |  |  |  |  |  |
|  |  |  |  |  | 98 | 62010800A-012-G |  | CAP,100pF,+/-5%,NPO(C0G),50V,G,SMD0402 | WALSIN TECHNOLOGY CORPORATION | 0402N101J500CT |  | G |  |  |  |  |  |  |  |
|  |  |  |  |  | 98 | 620108000-026-G |  | CAP,100pF,+/-5%,NPO(C0G),50V,G,SMD0402 | SAMSUNG SEMICONDUCTOR | CL05C101JB5NNNC |  | G |  |  |  |  |  |  |  |
|  |  |  |  |  | 98 | 620108000-023-G |  | CAP,100pF,+/-5%,NPO(C0G),50V,G,SMD0402 | TAIYO ELECTRIC IND.CO.LTD | UMK105CG101JV-F |  | G |  |  |  |  |  |  |  |
|  |  |  |  | 99 | 99 | 62013BS00-015-G |  | CAP,3nF,+/-10%,X7R,50V,G,SMD0402 | MURATA ELEC. NORTH AMERICA | GRM155R71H302KA01D | 1 | G | PSCC10 |  |  |  |  |  |  |
|  |  |  |  |  | 99 | 62013BS00-012-G |  | CAP,3nF,+/-10%,X7R,50V,G,SMD0402 | WALSIN TECHNOLOGY CORPORATION | 0402B302K500CT |  | G |  |  |  |  |  |  |  |
|  |  |  |  | 100 | 100 | 62010FF00-015-G | - | CAP,47pF,+/-5%,NPO(C0G),50V,G,SMD0402 | MURATA ELEC. NORTH AMERICA | GRM1555C1H470J | 1 | G | PSCC11 |  |  |  |  |  |  |
|  |  |  |  |  | 100 | 62010FF06-012-G |  | CAP,47pF,+/-5%,NPO(C0G),50V,G,SMD0402 | WALSIN TECHNOLOGY CORPORATION | 0402N470J500CT |  | G |  |  |  |  |  |  |  |
|  |  |  |  |  | 100 | 62010FF00-026-G |  | CAP,47pF,+/-5%,NPO(C0G),50V,G,SMD0402 | SAMSUNG SEMICONDUCTOR | CL05C470JB5NNNC |  | G |  |  |  |  |  |  |  |
|  |  |  |  |  | 100 | 62010FF00-023-G |  | CAP,47pF,+/-5%,NPO(C0G),50V,G,SMD0402 | TAIYO ELECTRIC IND.CO.LTD | UMK105CG470JV-F |  | G |  |  |  |  |  |  |  |
|  |  |  |  | 101 | 101 | 620107L00-015-G | - | CAP,2.2nF,+/-10%,X7R,50V,G,SMD0402 | MURATA ELEC. NORTH AMERICA | GRM155R71H222K | 1 | G | PSCC12 |  |  |  |  |  |  |
|  |  |  |  |  | 101 | 620107L00-012-G |  | CAP,2.2nF,+/-10%,X7R,50V,G,SMD0402 | WALSIN TECHNOLOGY CORPORATION | 0402B222K500CT |  | G |  |  |  |  |  |  |  |
|  |  |  |  |  | 101 | 620107L00-026-G |  | CAP,2.2nF,+/-10%,X7R,50V,G,SMD0402 | SAMSUNG SEMICONDUCTOR | CL05B222KB5NNNC |  | G |  |  |  |  |  |  |  |
|  |  |  |  |  | 101 | 620107L03-023-G |  | CAP,2.2nF,+/-10%,X7R,50V,G,SMD0402 | TAIYO ELECTRIC IND.CO.LTD | UMK105B7222KV-F |  | G |  |  |  |  |  |  |  |
|  |  |  |  | 102 | 102 | 62012T300-015-G | - | CAP,1uF,+/-10%,X7S,25V,G,SMD0402 | MURATA ELEC. NORTH AMERICA | GRM155C71E105KE11D | 4 | G | PSRC4,PSLC4,PSGC4,PSCC3003 |  |  |  |  |  |  |
|  |  |  |  |  | 102 | 620138700-026-G |  | CAP,1uF,+/-10%,X6S,25V,G,SMD0402 | SAMSUNG SEMICONDUCTOR | CL05X105KA5NQNC |  | G |  |  |  |  |  |  |  |
|  |  |  |  |  | 102 | 620138700-015-G |  | CAP,1uF,+/-10%,X6S,25V,G,SMD0402 | MURATA ELEC. NORTH AMERICA | GRM155C81E105KE11D |  | G |  |  |  |  |  |  |  |
|  |  |  |  | 103 | 103 | 63034FP00-088-G |  | IND,220nH@100KHz,+/-20%,23A,2.8mOhm,SHLD,G,SMD | COOPER BUSSMANN, INC. | HCM0703-R22-R | 1 | G | PSCL1 |  |  |  |  |  |  |
|  |  |  |  | 104 | 104 | 630341400-088-G | - | IND,22nH@1MHz,+/-20%,19A,368uOhm,SHLD,G,SMD | COOPER BUSSMANN, INC. | FP0404R1-R022-R | 1 | G | PSCL2 |  |  |  |  |  |  |
|  |  |  |  | 105 | 105 | 61100J300-017-G |  | RES,121 Ohm,+/-0.1%,1/16W,G,SMD0402 | KOA SPEER ELECTRONICS, INC. | RN731ETTP1210B25 | 1 | G | PSCR5 |  |  |  |  |  |  |
|  |  |  |  | 106 | 106 | 61100U300-017-G |  | RES,210 Ohm,+/-0.1%,1/16W,G,SMD0402 | KOA SPEER ELECTRONICS, INC. | RN731ETTP2100B25 | 1 | G | PSCR6 |  |  |  |  |  |  |
|  |  |  |  | 107 | 107 | 61011C400-017-G | - | RES,4.32KOhm,+/-1%,1/16W,G,SMD0402 | KOA SPEER ELECTRONICS, INC. | RK73H1ETTP4321F | 1 | G | PSCR10 |  |  |  |  |  |  |
|  |  |  |  |  | 107 | 61011C400-012-G |  | RES,4.32KOhm,+/-1%,1/16W,G,SMD0402 | WALSIN TECHNOLOGY CORPORATION | WR04X4321FTL |  | G |  |  |  |  |  |  |  |
|  |  |  |  |  | 107 | 61011C400-011-G |  | RES,4.32KOhm,+/-1%,1/16W,G,SMD0402 | YAGEO CORPORATION COMPONENT | RC0402FR-074K32L |  | G |  |  |  |  |  |  |  |
|  |  |  |  |  | 107 | 61011C400-044-G |  | RES,4.32KOhm,+/-1%,1/16W,G,SMD0402 | TA-I TECHNOLOGY CO., LTD. | RM04FTN4321 |  | G |  |  |  |  |  |  |  |
|  |  |  |  | 108 | 108 | 610112J00-017-G | - | RES,200 Ohm,+/-1%,1/16W,G,SMD0402 | KOA SPEER ELECTRONICS, INC. | RK73H1ETTP2000F | 1 | G | PSCR11 |  |  |  |  |  |  |
|  |  |  |  |  | 108 | 610112J00-012-G |  | RES,200 Ohm,+/-1%,1/16W,G,SMD0402 | WALSIN TECHNOLOGY CORPORATION | WR04X2000FTL |  | G |  |  |  |  |  |  |  |
|  |  |  |  |  | 108 | 610112J00-011-G |  | RES,200 Ohm,+/-1%,1/16W,G,SMD0402 | YAGEO CORPORATION COMPONENT | RC0402FR-07200RL |  | G |  |  |  |  |  |  |  |
|  |  |  |  |  | 108 | 610112J00-044-G |  | RES,200 Ohm,+/-1%,1/16W,G,SMD0402 | TA-I TECHNOLOGY CO., LTD. | RM04FTN2000 |  | G |  |  |  |  |  |  |  |
|  |  |  |  |  | 108 | 610112J00-029-G |  | RES,200 Ohm,+/-1%,1/16W,G,SMD0402 | VISHAY ENTER TECHNO LOGY.INC | CRCW0402200RFKED |  | G |  |  |  |  |  |  |  |
|  |  |  |  |  | 108 | 610112J00-024-G |  | RES,200 Ohm,+/-1%,1/16W,G,SMD0402 | PANASONIC INDUSTRIAL CO.,LTD. | ERJ2RKF2000X |  | G |  |  |  |  |  |  |  |
|  |  |  |  | 109 | 109 | 61011JY00-017-G | - | RES,39.2KOhm,+/-1%,1/16W,G,SMD0402 | KOA SPEER ELECTRONICS, INC. | RK73H1ETTP3922F | 1 | G | PSCR15 |  |  |  |  |  |  |
|  |  |  |  |  | 109 | 61011JY00-012-G |  | RES,39.2KOhm,+/-1%,1/16W,G,SMD0402 | WALSIN TECHNOLOGY CORPORATION | WR04X3922FTL |  | G |  |  |  |  |  |  |  |
|  |  |  |  |  | 109 | 61011JY00-011-G |  | RES,39.2KOhm,+/-1%,1/16W,G,SMD0402 | YAGEO CORPORATION COMPONENT | RC0402FR-0739K2L |  | G |  |  |  |  |  |  |  |
|  |  |  |  |  | 109 | 61011JY00-044-G |  | RES,39.2KOhm,+/-1%,1/16W,G,SMD0402 | TA-I TECHNOLOGY CO., LTD. | RM04FTN3922 |  | G |  |  |  |  |  |  |  |
|  |  |  |  |  | 109 | 61011JY00-029-G |  | RES,39.2KOhm,+/-1%,1/16W,G,SMD0402 | VISHAY ENTER TECHNO LOGY.INC | CRCW040239K2FKED |  | G |  |  |  |  |  |  |  |
|  |  |  |  | 110 | 110 | 61011RF00-017-G |  | RES,1.8KOhm,+/-1%,1/8W,G,SMD0805 | KOA SPEER ELECTRONICS, INC. | RK73H2ATTD1801F | 2 | G | PSGR20,PSCR3000 |  |  |  |  |  |  |
|  |  |  |  |  | 110 | 61011RF00-011-G |  | RES,1.8KOhm,+/-1%,1/8W,G,SMD0805 | YAGEO CORPORATION COMPONENT | RC0805FR-071K8L |  | G |  |  |  |  |  |  |  |
|  |  |  |  |  | 110 | 61011RF00-012-G |  | RES,1.8KOhm,+/-1%,1/8W,G,SMD0805 | WALSIN TECHNOLOGY CORPORATION | WR08X1801FTL |  | G |  |  |  |  |  |  |  |
|  |  |  |  | 111 | 111 | 32013HH00-238-G |  | IC,Regulator,IR3447MTRPBF,ADJ,25A,G,PQFN-33 | INTERNATIONAL RECTIFIER | IR3447MTRPBF | 1 | G | PSCU1 |  |  |  |  |  |  |
|  |  |  |  | 112 | 112 | 62012CM01-015-G |  | CAP,10uF,+/-20%,X6S,4V,G,SMD0603 | MURATA ELEC. NORTH AMERICA | GRM188C80G106M | 2 | G | PSLC16,PSGC16 |  |  |  |  |  |  |
|  |  |  |  |  | 112 | 62012CM00-023-G |  | CAP,10uF,+/-20%,X6S,4V,G,SMD0603 | TAIYO ELECTRIC IND.CO.LTD | AMK107AC6106MA-T |  | G |  |  |  |  |  |  |  |
|  |  |  |  |  | 112 | 62012CM00-026-G |  | CAP,10uF,+/-20%,X6S,4V,G,SMD0603 | SAMSUNG SEMICONDUCTOR | CL10X106MR8NNNC |  | G |  |  |  |  |  |  |  |
|  |  |  |  | 113 | 113 | 63033JK00-15A-G |  | IND,2.2uH@100KHz,+/-20%,9A,16.5mOhm,SHLD,G,SMD | The Inter-Technical Group, Inc. | SMHC2511A-2R2MHF | 1 | G | PSGL2 |  |  |  |  |  |  |
|  |  |  |  | 114 | 114 | 61010G500-017-G | - | RES,10KOhm,+/-1%,1/16W,G,SMD0402 | KOA SPEER ELECTRONICS, INC. | RK73H1ETTP1002F | 62 | G | PSRR6,PSLR6,PSGR6,R18,R40,R41,R42,R43,R44,R45,R46,R89,R90,R91,R102,R103,R104,R127,R128,R129,R130,R134,R139,R141,R234,R248,R342,R343,R344,R345,R346,R347,R348,R349,R350,R351,R352,R353,R354,R355,R356,R357,R358,R359,R360,R361,R371,R397,R398,R404,R405,R406,R407,R442,R443,R1487,R1493,R1497,R1501,R1511,R1512,R1544, |  |  |  |  |  |  |
|  |  |  |  |  | 114 | 61010G500-012-G |  | RES,10KOhm,+/-1%,1/16W,G,SMD0402 | WALSIN TECHNOLOGY CORPORATION | WR04X1002FTL |  | G |  |  |  |  |  |  |  |
|  |  |  |  |  | 114 | 61010G500-011-G |  | RES,10KOhm,+/-1%,1/16W,G,SMD0402 | YAGEO CORPORATION COMPONENT | RC0402FR-0710KL |  | G |  |  |  |  |  |  |  |
|  |  |  |  |  | 114 | 61010G500-044-G |  | RES,10KOhm,+/-1%,1/16W,G,SMD0402 | TA-I TECHNOLOGY CO., LTD. | RM04FTN1002 |  | G |  |  |  |  |  |  |  |
|  |  |  |  |  | 114 | 61010G500-029-G |  | RES,10KOhm,+/-1%,1/16W,G,SMD0402 | VISHAY ENTER TECHNO LOGY.INC | CRCW040210K0FKED |  | G |  |  |  |  |  |  |  |
|  |  |  |  |  | 114 | 61010G500-024-G |  | RES,10KOhm,+/-1%,1/16W,G,SMD0402 | PANASONIC INDUSTRIAL CO.,LTD. | ERJ2RKF1002X |  | G |  |  |  |  |  |  |  |
|  |  |  |  | 115 | 115 | 61100QY00-011-G |  | RES,17.4KOhm,+/-0.1%,1/16W,G,SMD0402 | YAGEO CORPORATION COMPONENT | RT0402BRD0717K4L | 1 | G | PSGR17 |  |  |  |  |  |  |
|  |  |  |  | 116 | 116 | 61100PL00-011-G |  | RES,10.2KOhm,+/-0.1%,1/16W,G,SMD0402 | YAGEO CORPORATION COMPONENT | RT0402BRD0710K2L | 1 | G | PSGR19 |  |  |  |  |  |  |
|  |  |  |  | 117 | 117 | 32013PD00-238-G |  | IC,Regulator,IR3883MTRPbF,ADJ,3A,G,QFN-16,SMD | INTERNATIONAL RECTIFIER | IR3883MTRPBF | 3 | G | PSRU1,PSLU1,PSGU1 |  |  |  |  |  |  |
|  |  |  |  | 118 | 118 | 630328U00-088-G |  | IND,3.3uH@100KHz,+/-20%,6A,30mOhm,SHLD,G,SMD | COOPER BUSSMANN, INC. | HCM0703-3R3-R | 1 | G | PSLL2 |  |  |  |  |  |  |
|  |  |  |  | 119 | 119 | 61100DF00-017-G |  | RES,6.34KOhm,+/-0.1%,1/16W,G,SMD0402 | KOA SPEER ELECTRONICS, INC. | RN731ETTP6341B25 | 1 | G | PSLR19 |  |  |  |  |  |  |
|  |  |  |  | 120 | 120 | 620105U00-015-G | - | CAP,220pF,+/-10%,X7R,50V,G,SMD0402 | MURATA ELEC. NORTH AMERICA | GRM155R71H221K | 1 | G | PSRC14 |  |  |  |  |  |  |
|  |  |  |  |  | 120 | 620105U00-012-G |  | CAP,220pF,+/-10%,X7R,50V,G,SMD0402 | WALSIN TECHNOLOGY CORPORATION | 0402B221K500CT |  | G |  |  |  |  |  |  |  |
|  |  |  |  |  | 120 | 620105U00-026-G |  | CAP,220pF,+/-10%,X7R,50V,G,SMD0402 | SAMSUNG SEMICONDUCTOR | CL05B221KB5NNNC |  | G |  |  |  |  |  |  |  |
|  |  |  |  | 121 | 121 | 63032PP00-088-G |  | IND,4.7uH@100KHz,+/-20%,5.5A,40mOhm,SHLD,G,SMD | COOPER BUSSMANN, INC. | HCM0703-4R7-R | 1 | G | PSRL2 |  |  |  |  |  |  |
|  |  |  |  | 122 | 122 | 610117D00-017-G | - | RES,13.3KOhm,+/-1%,1/16W,G,SMD0402 | KOA SPEER ELECTRONICS, INC. | RK73H1ETTP1332F | 1 | G | PSRR1 |  |  |  |  |  |  |
|  |  |  |  |  | 122 | 610117D00-012-G |  | RES,13.3KOhm,+/-1%,1/16W,G,SMD0402 | WALSIN TECHNOLOGY CORPORATION | WR04X1332FTL |  | G |  |  |  |  |  |  |  |
|  |  |  |  |  | 122 | 610117D00-011-G |  | RES,13.3KOhm,+/-1%,1/16W,G,SMD0402 | YAGEO CORPORATION COMPONENT | RC0402FR-0713K3L |  | G |  |  |  |  |  |  |  |
|  |  |  |  |  | 122 | 610117D00-044-G |  | RES,13.3KOhm,+/-1%,1/16W,G,SMD0402 | TA-I TECHNOLOGY CO., LTD. | RM04FTN1332 |  | G |  |  |  |  |  |  |  |
|  |  |  |  | 123 | 123 | 61100YB00-017-G |  | RES,2.94KOhm,+/-0.1%,1/16W,G,SMD0402 | KOA SPEER ELECTRONICS, INC. | RN731ETTP2941B25 | 1 | G | PSRR19 |  |  |  |  |  |  |
|  |  |  |  | 124 | 124 | 510503B00-223-G |  | MOS N/N,NTZD3154NT1G,20V,0.54A,550m24.5V,G,SOT563-6,SMD | ON SEMICONDUCTOR CORP | NTZD3154NT1G | 4 | G | QN1,QN2,QN3,QN5 |  |  |  |  |  |  |
|  |  |  |  | 125 | 125 | 510501900-237-G | - | MOS N/N,2N7002DW-7-F,60V,0.115A,7.5ohm@5V,G,SOT363-6,SMD | DIODES INEORPORATION | 2N7002DW-7-F | 1 | G | QN4 |  |  |  |  |  |  |
|  |  |  |  | 126 | 126 | 510309C00-237-G |  | MOS N,BSS138-7-F,50V,0.2A,3.5ohm@10V,G,SOT23-3,SMD | DIODES INCORPORATION | BSS138-7-F | 5 | G | Q1,Q2,Q3,Q8,Q9 |  |  |  |  |  |  |
|  |  |  |  | 127 | 127 | 51040EK00-185-G |  | MOS P,FDMS6681Z,30V,49A,5m@4.5V,G,Power56-8,SMD | FAIRCHILD SEMICONDUCTOR CORP | FDMS6681Z | 2 | G | Q4,Q6 |  |  |  |  |  |  |
|  |  |  |  | 128 | 128 | 51030S400-185-G |  | MOS N,FDMC8884,30V,9A,30m@4.5V,G,Power33-8,SMD | FAIRCHILD SEMICONDUCTOR CORP | FDMC8884 | 1 | G | Q5 |  |  |  |  |  |  |
|  |  |  |  | 129 | 129 | 51030CQ00-185-G |  | MOS N,2N7002,60V,115mA,7.5ohm@5V,G,SOT23-3,SMD | FAIRCHILD SEMICONDUCTOR CORP | 2N7002 | 1 | G | Q7 |  |  |  |  |  |  |
|  |  |  |  | 130 | 130 | 61010H800-017-G |  | RES,5.11 Ohm,+/-1%,1/10W,G,SMD0603 | KOA SPEER ELECTRONICS, INC. | RK73H1JTTD5R11F | 1 | G | R4 |  |  |  |  |  |  |
|  |  |  |  |  | 130 | 61010H800-012-G |  | RES,5.11 Ohm,+/-1%,1/10W,G,SMD0603 | WALSIN TECHNOLOGY CORPORATION | WR06W5R11FTL |  | G |  |  |  |  |  |  |  |
|  |  |  |  |  | 130 | 61010H800-011-G |  | RES,5.11 Ohm,+/-1%,1/10W,G,SMD0603 | YAGEO CORPORATION COMPONENT | RC0603FR-075R11L |  | G |  |  |  |  |  |  |  |
|  |  |  |  |  | 130 | 61010H800-044-G |  | RES,5.11 Ohm,+/-1%,1/10W,G,SMD0603 | TA-I TECHNOLOGY CO., LTD. | RM06FTN5R11 |  | G |  |  |  |  |  |  |  |
|  |  |  |  | 131 | 131 | 61011MQ00-017-G | - | RES,4.75KOhm,+/-1%,1/16W,G,SMD0402 | KOA SPEER ELECTRONICS, INC. | RK73H1ETTP4751F | 15 | G | R5,R28,R30,R34,R36,R78,R84,R92,R188,R195,R210,R211,R241,R242,R1446 |  |  |  |  |  |  |
|  |  |  |  |  | 131 | 61011MQ00-011-G |  | RES,4.75KOhm,+/-1%,1/16W,G,SMD0402 | YAGEO CORPORATION COMPONENT | RC0402FR-074K75L |  | G |  |  |  |  |  |  |  |
|  |  |  |  |  | 131 | 61011MQ00-012-G |  | RES,4.75KOhm,+/-1%,1/16W,G,SMD0402 | WALSIN TECHNOLOGY CORPORATION | WR04X4751FTL |  | G |  |  |  |  |  |  |  |
|  |  |  |  |  | 131 | 61011MQ00-044-G |  | RES,4.75KOhm,+/-1%,1/16W,G,SMD0402 | TA-I TECHNOLOGY CO., LTD. | RM04FTN4751 |  | G |  |  |  |  |  |  |  |
|  |  |  |  | 132 | 132 | 61011KB00-017-G | - | RES,51.1 Ohm,+/-1%,1/16W,G,SMD0402 | KOA SPEER ELECTRONICS, INC. | RK73H1ETTP51R1F | 4 | G | R6,R8,R9,R10 |  |  |  |  |  |  |
|  |  |  |  |  | 132 | 61011KB00-011-G |  | RES,51.1 Ohm,+/-1%,1/16W,G,SMD0402 | YAGEO CORPORATION COMPONENT | RC0402FR-0751R1L |  | G |  |  |  |  |  |  |  |
|  |  |  |  |  | 132 | 61011KB00-012-G |  | RES,51.1 Ohm,+/-1%,1/16W,G,SMD0402 | WALSIN TECHNOLOGY CORPORATION | WR04X51R1FTL |  | G |  |  |  |  |  |  |  |
|  |  |  |  |  | 132 | 61011KB00-044-G |  | RES,51.1 Ohm,+/-1%,1/16W,G,SMD0402 | TA-I TECHNOLOGY CO., LTD. | RM04FTN51R1 |  | G |  |  |  |  |  |  |  |
|  |  |  |  | 133 | 133 | 61011BH00-017-G |  | RES,22.1 Ohm,+/-1%,1/16W,G,SMD0402 | KOA SPEER ELECTRONICS, INC. | RK73H1ETTP22R1F | 3 | G | R12,R13,R136 |  |  |  |  |  |  |
|  |  |  |  |  | 133 | 61011BH00-012-G |  | RES,22.1 Ohm,+/-1%,1/16W,G,SMD0402 | WALSIN TECHNOLOGY CORPORATION | WR04X22R1FTL |  | G |  |  |  |  |  |  |  |
|  |  |  |  |  | 133 | 61011BH00-011-G |  | RES,22.1 Ohm,+/-1%,1/16W,G,SMD0402 | YAGEO CORPORATION COMPONENT | RC0402FR-0722R1L |  | G |  |  |  |  |  |  |  |
|  |  |  |  |  | 133 | 61011BH00-044-G |  | RES,22.1 Ohm,+/-1%,1/16W,G,SMD0402 | TA-I TECHNOLOGY CO., LTD. | RM04FTN22R1 |  | G |  |  |  |  |  |  |  |
|  |  |  |  | 134 | 134 | 61011M600-017-G |  | RES,82.5 Ohm,+/-1%,1/16W,G,SMD0402 | KOA SPEER ELECTRONICS, INC. | RK73H1ETTP82R5F | 1 | G | R14 |  |  |  |  |  |  |
|  |  |  |  |  | 134 | 61011M600-011-G |  | RES,82.5 Ohm,+/-1%,1/16W,G,SMD0402 | YAGEO CORPORATION COMPONENT | RC0402FR-0782R5L |  | G |  |  |  |  |  |  |  |
|  |  |  |  |  | 134 | 61011M600-012-G |  | RES,82.5 Ohm,+/-1%,1/16W,G,SMD0402 | WALSIN TECHNOLOGY CORPORATION | WR04X82R5FTL |  | G |  |  |  |  |  |  |  |
|  |  |  |  | 135 | 135 | 610112W00-017-G |  | RES,2KOhm,+/-5%,1/16W,G,SMD0402 | KOA SPEER ELECTRONICS, INC. | RK73B1ETTP202J | 37 | G | R15,R17,R27,R29,R38,R39,R48,R49,R50,R51,R53,R54,R55,R57,R58,R59,R60,R61,R62,R63,R64,R65,R66,R67,R68,R69,R79,R80,R81,R82,R83,R87,R93,R95,R97,R98,R99 |  |  |  |  |  |  |
|  |  |  |  |  | 135 | 610112W00-012-G |  | RES,2KOhm,+/-5%,1/16W,G,SMD0402 | WALSIN TECHNOLOGY CORPORATION | WR04X202JTL |  | G |  |  |  |  |  |  |  |
|  |  |  |  |  | 135 | 610112W00-011-G |  | RES,2KOhm,+/-5%,1/16W,G,SMD0402 | YAGEO CORPORATION COMPONENT | RC0402JR-072KL |  | G |  |  |  |  |  |  |  |
|  |  |  |  |  | 135 | 610112W00-044-G |  | RES,2KOhm,+/-5%,1/16W,G,SMD0402 | TA-I TECHNOLOGY CO., LTD. | RM04JTN202 |  | G |  |  |  |  |  |  |  |
|  |  |  |  |  | 135 | 610112W00-024-G |  | RES,2KOhm,+/-5%,1/16W,G,SMD0402 | PANASONIC INDUSTRIAL CO.,LTD. | ERJ2GEJ202X |  | G |  |  |  |  |  |  |  |
|  |  |  |  | 136 | 136 | 610114E00-017-G |  | RES,33.2 Ohm,+/-1%,1/16W,G,SMD0402 | KOA SPEER ELECTRONICS, INC. | RK73H1ETTP33R2F | 1 | G | R16 |  |  |  |  |  |  |
|  |  |  |  |  | 136 | 610114E00-012-G |  | RES,33.2 Ohm,+/-1%,1/16W,G,SMD0402 | WALSIN TECHNOLOGY CORPORATION | WR04X33R2FTL |  | G |  |  |  |  |  |  |  |
|  |  |  |  |  | 136 | 610114E00-011-G |  | RES,33.2 Ohm,+/-1%,1/16W,G,SMD0402 | YAGEO CORPORATION COMPONENT | RC0402FR-0733R2L |  | G |  |  |  |  |  |  |  |
|  |  |  |  |  | 136 | 610114E00-044-G |  | RES,33.2 Ohm,+/-1%,1/16W,G,SMD0402 | TA-I TECHNOLOGY CO., LTD. | RM04FTN33R2 |  | G |  |  |  |  |  |  |  |
|  |  |  |  | 137 | 137 | 610114J00-017-G | - | RES,2KOhm,+/-1%,1/16W,G,SMD0402 | KOA SPEER ELECTRONICS, INC. | RK73H1ETTP2001F | 1 | G | R26 |  |  |  |  |  |  |
|  |  |  |  |  | 137 | 610114J00-012-G |  | RES,2KOhm,+/-1%,1/16W,G,SMD0402 | WALSIN TECHNOLOGY CORPORATION | WR04X2001FTL |  | G |  |  |  |  |  |  |  |
|  |  |  |  |  | 137 | 610114J00-011-G |  | RES,2KOhm,+/-1%,1/16W,G,SMD0402 | YAGEO CORPORATION COMPONENT | RC0402FR-072KL |  | G |  |  |  |  |  |  |  |
|  |  |  |  |  | 137 | 610114J00-044-G |  | RES,2KOhm,+/-1%,1/16W,G,SMD0402 | TA-I TECHNOLOGY CO., LTD. | RM04FTN2001 |  | G |  |  |  |  |  |  |  |
|  |  |  |  |  | 137 | 610114J00-024-G |  | RES,2KOhm,+/-1%,1/16W,G,SMD0402 | PANASONIC INDUSTRIAL CO.,LTD. | ERJ2RKF2001X |  | G |  |  |  |  |  |  |  |
|  |  |  |  |  | 137 | 610114J00-029-G |  | RES,2KOhm,+/-1%,1/16W,G,SMD0402 | VISHAY ENTER TECHNO LOGY.INC | CRCW04022K00FKED |  | G |  |  |  |  |  |  |  |
|  |  |  |  | 138 | 138 | 61010JY00-017-G | - | RES,220 Ohm,+/-5%,1/16W,G,SMD0402 | KOA SPEER ELECTRONICS, INC. | RK73B1ETTP221J | 5 | G | R192,R194,R200,R201,R203 |  |  |  |  |  |  |
|  |  |  |  |  | 138 | 61010JY00-012-G |  | RES,220 Ohm,+/-5%,1/16W,G,SMD0402 | WALSIN TECHNOLOGY CORPORATION | WR04X221JTL |  | G |  |  |  |  |  |  |  |
|  |  |  |  |  | 138 | 61010JY00-011-G |  | RES,220 Ohm,+/-5%,1/16W,G,SMD0402 | YAGEO CORPORATION COMPONENT | RC0402JR-07220RL |  | G |  |  |  |  |  |  |  |
|  |  |  |  |  | 138 | 61010JY00-044-G |  | RES,220 Ohm,+/-5%,1/16W,G,SMD0402 | TA-I TECHNOLOGY CO., LTD. | RM04JTN221 |  | G |  |  |  |  |  |  |  |
|  |  |  |  | 139 | 139 | 61012RW00-017-G |  | RES,510mOhm,+/-1%,1/8W,G,SMD0402 | KOA SPEER ELECTRONICS, INC. | SR731ETTPR510F | 12 | G | R115,R116,R117,R118,R119,R120,R121,R122,R123,R124,R125,R126 |  |  |  |  |  |  |
|  |  |  |  |  | 139 | 61012RW00-011-G |  | RES,510mOhm,+/-1%,1/8W,G,SMD0402 | YAGEO CORPORATION COMPONENT | PT0402FR-7W0R51L |  | G |  |  |  |  |  |  |  |
|  |  |  |  |  | 139 | 61012RW00-012-G |  | RES,510mOhm,+/-1%,1/8W,G,SMD0402 | WALSIN TECHNOLOGY CORPORATION | WW04PR510FTL |  | G |  |  |  |  |  |  |  |
|  |  |  |  | 140 | 140 | 61011T000-017-G |  | RES,82 Ohm,+/-1%,1/16W,G,SMD0402 | KOA SPEER ELECTRONICS, INC. | RK73H1ETTP82R0F | 42 | G | R143,R144,R145,R146,R147,R148,R149,R150,R151,R152,R153,R154,R155,R156,R157,R158,R159,R160,R161,R162,R163,R164,R165,R166,R167,R168,R169,R170,R171,R172,R173,R174,R175,R177,R178,R179,R180,R181,R182,R183,R184,R185 |  |  |  |  |  |  |
|  |  |  |  |  | 140 | 61011T000-011-G |  | RES,82 Ohm,+/-1%,1/16W,G,SMD0402 | YAGEO CORPORATION COMPONENT | RC0402FR-0782RL |  | G |  |  |  |  |  |  |  |
|  |  |  |  |  | 140 | 61011T000-012-G |  | RES,82 Ohm,+/-1%,1/16W,G,SMD0402 | WALSIN TECHNOLOGY CORPORATION | WR04X82R0FTL |  | G |  |  |  |  |  |  |  |
|  |  |  |  |  | 140 | 61011T000-044-G |  | RES,82 Ohm,+/-1%,1/16W,G,SMD0402 | TA-I TECHNOLOGY CO., LTD. | RM04FTN82R0 |  | G |  |  |  |  |  |  |  |
|  |  |  |  | 141 | 141 | 610101V00-017-G | K9572 | RES,22 Ohm,+/-5%,1/16W,G,SMD0402 | KOA SPEER ELECTRONICS, INC. | RK73B1ETTP220J | 1 | G | R190 |  |  |  |  |  |  |
|  |  |  |  |  | 141 | 610101V00-012-G |  | RES,22 Ohm,+/-5%,1/16W,G,SMD0402 | WALSIN TECHNOLOGY CORPORATION | WR04X220JTL |  | G |  |  |  |  |  |  |  |
|  |  |  |  |  | 141 | 610101V00-011-G |  | RES,22 Ohm,+/-5%,1/16W,G,SMD0402 | YAGEO CORPORATION COMPONENT | RC0402JR-0722RL |  | G |  |  |  |  |  |  |  |
|  |  |  |  |  | 141 | 610101V00-044-G |  | RES,22 Ohm,+/-5%,1/16W,G,SMD0402 | TA-I TECHNOLOGY CO., LTD. | RM04JTN220 |  | G |  |  |  |  |  |  |  |
|  |  |  |  |  | 141 | 610101V00-024-G |  | RES,22 Ohm,+/-5%,1/16W,G,SMD0402 | PANASONIC INDUSTRIAL CO.,LTD. | ERJ2GEJ220X |  | G |  |  |  |  |  |  |  |
|  |  |  |  | 142 | 142 | 61011H500-017-G | - | RES,22 Ohm,+/-1%,1/16W,G,SMD0402 | KOA SPEER ELECTRONICS, INC. | RK73H1ETTP22R0F | 1 | G | R202 |  |  |  |  |  |  |
|  |  |  |  |  | 142 | 61011H500-012-G |  | RES,22 Ohm,+/-1%,1/16W,G,SMD0402 | WALSIN TECHNOLOGY CORPORATION | WR04X22R0FTL |  | G |  |  |  |  |  |  |  |
|  |  |  |  |  | 142 | 61011H500-011-G |  | RES,22 Ohm,+/-1%,1/16W,G,SMD0402 | YAGEO CORPORATION COMPONENT | RC0402FR-0722RL |  | G |  |  |  |  |  |  |  |
|  |  |  |  |  | 142 | 61011H500-044-G |  | RES,22 Ohm,+/-1%,1/16W,G,SMD0402 | TA-I TECHNOLOGY CO., LTD. | RM04FTN22R0 |  | G |  |  |  |  |  |  |  |
|  |  |  |  |  | 142 | 61011H500-024-G |  | RES,22 Ohm,+/-1%,1/16W,G,SMD0402 | PANASONIC INDUSTRIAL CO.,LTD. | ERJ2RKF22R0X |  | G |  |  |  |  |  |  |  |
|  |  |  |  | 143 | 143 | 610100T00-017-G |  | RES,1KOhm,+/-5%,1/16W,G,SMD0402 | KOA SPEER ELECTRONICS, INC. | RK73B1ETTP102J | 7 | G | R208,R209,R218,R219,R224,R225,R1510 |  |  |  |  |  |  |
|  |  |  |  |  | 143 | 610100T00-012-G |  | RES,1KOhm,+/-5%,1/16W,G,SMD0402 | WALSIN TECHNOLOGY CORPORATION | WR04X102JTL |  | G |  |  |  |  |  |  |  |
|  |  |  |  |  | 143 | 610100T00-011-G |  | RES,1KOhm,+/-5%,1/16W,G,SMD0402 | YAGEO CORPORATION COMPONENT | RC0402JR-071KL |  | G |  |  |  |  |  |  |  |
|  |  |  |  |  | 143 | 610100T00-044-G |  | RES,1KOhm,+/-5%,1/16W,G,SMD0402 | TA-I TECHNOLOGY CO., LTD. | RM04JTN102 |  | G |  |  |  |  |  |  |  |
|  |  |  |  |  | 143 | 610100T00-024-G |  | RES,1KOhm,+/-5%,1/16W,G,SMD0402 | PANASONIC INDUSTRIAL CO.,LTD. | ERJ2GEJ102X |  | G |  |  |  |  |  |  |  |
|  |  |  |  | 144 | 144 | 610107B00-017-G | K9576 | RES,4.7KOhm,+/-5%,1/16W,G,SMD0402 | KOA SPEER ELECTRONICS, INC. | RK73B1ETTP472J | 4 | G | R228,R1415,R1440,R1517 |  |  |  |  |  |  |
|  |  |  |  |  | 144 | 610107B00-012-G |  | RES,4.7KOhm,+/-5%,1/16W,G,SMD0402 | WALSIN TECHNOLOGY CORPORATION | WR04X472JTL |  | G |  |  |  |  |  |  |  |
|  |  |  |  |  | 144 | 610107B00-011-G |  | RES,4.7KOhm,+/-5%,1/16W,G,SMD0402 | YAGEO CORPORATION COMPONENT | RC0402JR-074K7L |  | G |  |  |  |  |  |  |  |
|  |  |  |  |  | 144 | 610107B00-044-G |  | RES,4.7KOhm,+/-5%,1/16W,G,SMD0402 | TA-I TECHNOLOGY CO., LTD. | RM04JTN472 |  | G |  |  |  |  |  |  |  |
|  |  |  |  |  | 144 | 610107B00-024-G |  | RES,4.7KOhm,+/-5%,1/16W,G,SMD0402 | PANASONIC INDUSTRIAL CO.,LTD. | ERJ2GEJ472X |  | G |  |  |  |  |  |  |  |
|  |  |  |  |  | 144 | 610107B00-029-G |  | RES,4.7KOhm,+/-5%,1/16W,G,SMD0402 | VISHAY ENTER TECHNO LOGY.INC | CRCW04024K70JNED |  | G |  |  |  |  |  |  |  |
|  |  |  |  | 145 | 145 | 61010L100-017-G | - | RES,100KOhm,+/-1%,1/16W,G,SMD0402 | KOA SPEER ELECTRONICS, INC. | RK73H1ETTP1003F | 3 | G | R233,R238,R245 |  |  |  |  |  |  |
|  |  |  |  |  | 145 | 61010L100-012-G |  | RES,100KOhm,+/-1%,1/16W,G,SMD0402 | WALSIN TECHNOLOGY CORPORATION | WR04X1003FTL |  | G |  |  |  |  |  |  |  |
|  |  |  |  |  | 145 | 61010L100-011-G |  | RES,100KOhm,+/-1%,1/16W,G,SMD0402 | YAGEO CORPORATION COMPONENT | RC0402FR-07100KL |  | G |  |  |  |  |  |  |  |
|  |  |  |  |  | 145 | 61010L100-044-G |  | RES,100KOhm,+/-1%,1/16W,G,SMD0402 | TA-I TECHNOLOGY CO., LTD. | RM04FTN1003 |  | G |  |  |  |  |  |  |  |
|  |  |  |  |  | 145 | 61010L106-029-G |  | RES,100KOhm,+/-1%,1/16W,G,SMD0402 | VISHAY ENTER TECHNO LOGY.INC | CRCW0402100KFKEDC |  | G |  |  |  |  |  |  |  |
|  |  |  |  |  | 145 | 61010L100-024-G |  | RES,100KOhm,+/-1%,1/16W,G,SMD0402 | PANASONIC INDUSTRIAL CO.,LTD. | ERJ2RKF1003X |  | G |  |  |  |  |  |  |  |
|  |  |  |  | 146 | 146 | 61011WQ00-017-G | - | RES,3KOhm,+/-1%,1/16W,G,SMD0402 | KOA SPEER ELECTRONICS, INC. | RK73H1ETTP3001F | 56 | G | R255,R256,R257,R258,R259,R260,R261,R262,R263,R268,R269,R270,R271,R272,R273,R274,R275,R276,R281,R282,R283,R284,R285,R286,R287,R288,R289,R297,R298,R299,R300,R301,R302,R303,R304,R305,R310,R311,R312,R313,R314,R315,R316,R317,R318,R326,R327,R328,R329,R330,R331,R332,R333,R334,R383,R384 |  |  |  |  |  |  |
|  |  |  |  |  | 146 | 61011WQ00-012-G |  | RES,3KOhm,+/-1%,1/16W,G,SMD0402 | WALSIN TECHNOLOGY CORPORATION | WR04X3001FTL |  | G |  |  |  |  |  |  |  |
|  |  |  |  |  | 146 | 61011WQ00-011-G |  | RES,3KOhm,+/-1%,1/16W,G,SMD0402 | YAGEO CORPORATION COMPONENT | RC0402FR-073KL |  | G |  |  |  |  |  |  |  |
|  |  |  |  |  | 146 | 61011WQ00-044-G |  | RES,3KOhm,+/-1%,1/16W,G,SMD0402 | TA-I TECHNOLOGY CO., LTD. | RM04FTN3001 |  | G |  |  |  |  |  |  |  |
|  |  |  |  | 147 | 147 | 61011B000-017-G | - | RES,1.5KOhm,+/-1%,1/16W,G,SMD0402 | KOA SPEER ELECTRONICS, INC. | RK73H1ETTP1501F | 1 | G | R382 |  |  |  |  |  |  |
|  |  |  |  |  | 147 | 61011B000-012-G |  | RES,1.5KOhm,+/-1%,1/16W,G,SMD0402 | WALSIN TECHNOLOGY CORPORATION | WR04X1501FTL |  | G |  |  |  |  |  |  |  |
|  |  |  |  |  | 147 | 61011B000-011-G |  | RES,1.5KOhm,+/-1%,1/16W,G,SMD0402 | YAGEO CORPORATION COMPONENT | RC0402FR-071K5L |  | G |  |  |  |  |  |  |  |
|  |  |  |  |  | 147 | 61011B000-044-G |  | RES,1.5KOhm,+/-1%,1/16W,G,SMD0402 | TA-I TECHNOLOGY CO., LTD. | RM04FTN1501 |  | G |  |  |  |  |  |  |  |
|  |  |  |  |  | 147 | 61011B000-024-G |  | RES,1.5KOhm,+/-1%,1/16W,G,SMD0402 | PANASONIC INDUSTRIAL CO.,LTD. | ERJ2RKF1501X |  | G |  |  |  |  |  |  |  |
|  |  |  |  | 148 | 148 | 610102700-017-G | - | RES,49.9 Ohm,+/-1%,1/16W,G,SMD0402 | KOA SPEER ELECTRONICS, INC. | RK73H1ETTP49R9F | 2 | G | R445,R448 |  |  |  |  |  |  |
|  |  |  |  |  | 148 | 610102700-012-G |  | RES,49.9 Ohm,+/-1%,1/16W,G,SMD0402 | WALSIN TECHNOLOGY CORPORATION | WR04X49R9FTL |  | G |  |  |  |  |  |  |  |
|  |  |  |  |  | 148 | 610102700-011-G |  | RES,49.9 Ohm,+/-1%,1/16W,G,SMD0402 | YAGEO CORPORATION COMPONENT | RC0402FR-0749R9L |  | G |  |  |  |  |  |  |  |
|  |  |  |  |  | 148 | 610102700-044-G |  | RES,49.9 Ohm,+/-1%,1/16W,G,SMD0402 | TA-I TECHNOLOGY CO., LTD. | RM04FTN49R9 |  | G |  |  |  |  |  |  |  |
|  |  |  |  |  | 148 | 610102700-029-G |  | RES,49.9 Ohm,+/-1%,1/16W,G,SMD0402 | VISHAY ENTER TECHNO LOGY.INC | CRCW040249R9FKED |  | G |  |  |  |  |  |  |  |
|  |  |  |  |  | 148 | 610102700-024-G |  | RES,49.9 Ohm,+/-1%,1/16W,G,SMD0402 | PANASONIC INDUSTRIAL CO.,LTD. | ERJ2RKF49R9X |  | G |  |  |  |  |  |  |  |
|  |  |  |  | 149 | 149 | 610115J00-017-G | - | RES,33 Ohm,+/-1%,1/16W,G,SMD0402 | KOA SPEER ELECTRONICS, INC. | RK73H1ETTP33R0F | 2 | G | R446,R447 |  |  |  |  |  |  |
|  |  |  |  |  | 149 | 610115J00-012-G |  | RES,33 Ohm,+/-1%,1/16W,G,SMD0402 | WALSIN TECHNOLOGY CORPORATION | WR04X33R0FTL |  | G |  |  |  |  |  |  |  |
|  |  |  |  |  | 149 | 610115J00-011-G |  | RES,33 Ohm,+/-1%,1/16W,G,SMD0402 | YAGEO CORPORATION COMPONENT | RC0402FR-0733RL |  | G |  |  |  |  |  |  |  |
|  |  |  |  |  | 149 | 610115J00-044-G |  | RES,33 Ohm,+/-1%,1/16W,G,SMD0402 | TA-I TECHNOLOGY CO., LTD. | RM04FTN33R0 |  | G |  |  |  |  |  |  |  |
|  |  |  |  |  | 149 | 610115J00-024-G |  | RES,33 Ohm,+/-1%,1/16W,G,SMD0402 | PANASONIC INDUSTRIAL CO.,LTD. | ERJ2RKF33R0X |  | G |  |  |  |  |  |  |  |
|  |  |  |  | 150 | 150 | 61011T800-017-G | - | RES,240 Ohm,+/-1%,1/16W,G,SMD0402 | KOA SPEER ELECTRONICS, INC. | RK73H1ETTP2400F | 1 | G | R454 |  |  |  |  |  |  |
|  |  |  |  |  | 150 | 61011T800-012-G |  | RES,240 Ohm,+/-1%,1/16W,G,SMD0402 | WALSIN TECHNOLOGY CORPORATION | WR04X2400FTL |  | G |  |  |  |  |  |  |  |
|  |  |  |  |  | 150 | 61011T800-011-G |  | RES,240 Ohm,+/-1%,1/16W,G,SMD0402 | YAGEO CORPORATION COMPONENT | RC0402FR-07240RL |  | G |  |  |  |  |  |  |  |
|  |  |  |  |  | 150 | 61011T800-044-G |  | RES,240 Ohm,+/-1%,1/16W,G,SMD0402 | TA-I TECHNOLOGY CO., LTD. | RM04FTN2400 |  | G |  |  |  |  |  |  |  |
|  |  |  |  | 151 | 151 | 610112500-017-G | - | RES,475 Ohm,+/-1%,1/16W,G,SMD0402 | KOA SPEER ELECTRONICS, INC. | RK73H1ETTP4750F | 1 | G | R1411 |  |  |  |  |  |  |
|  |  |  |  |  | 151 | 610112500-012-G |  | RES,475 Ohm,+/-1%,1/16W,G,SMD0402 | WALSIN TECHNOLOGY CORPORATION | WR04X4750FTL |  | G |  |  |  |  |  |  |  |
|  |  |  |  |  | 151 | 610112500-011-G |  | RES,475 Ohm,+/-1%,1/16W,G,SMD0402 | YAGEO CORPORATION COMPONENT | RC0402FR-07475RL |  | G |  |  |  |  |  |  |  |
|  |  |  |  |  | 151 | 610112500-044-G |  | RES,475 Ohm,+/-1%,1/16W,G,SMD0402 | TA-I TECHNOLOGY CO., LTD. | RM04FTN4750 |  | G |  |  |  |  |  |  |  |
|  |  |  |  | 152 | 152 | 610107L00-017-G |  | RES,1 Ohm,+/-5%,1/10W,G,SMD0603 | KOA SPEER ELECTRONICS, INC. | RK73B1JTTD1R0J | 1 | G | R1413 |  |  |  |  |  |  |
|  |  |  |  |  | 152 | 610107L00-011-G |  | RES,1 Ohm,+/-5%,1/10W,G,SMD0603 | YAGEO CORPORATION COMPONENT | RC0603JR-071RL |  | G |  |  |  |  |  |  |  |
|  |  |  |  |  | 152 | 610107L00-012-G |  | RES,1 Ohm,+/-5%,1/10W,G,SMD0603 | WALSIN TECHNOLOGY CORPORATION | WR06X1R0JTL |  | G |  |  |  |  |  |  |  |
|  |  |  |  |  | 152 | 610107L00-044-G |  | RES,1 Ohm,+/-5%,1/10W,G,SMD0603 | TA-I TECHNOLOGY CO., LTD. | RM06JTN1R0 |  | G |  |  |  |  |  |  |  |
|  |  |  |  | 153 | 153 | 610107C00-017-G | K9577 | RES,10KOhm,+/-5%,1/16W,G,SMD0402 | KOA SPEER ELECTRONICS, INC. | RK73B1ETTP103J | 1 | G | R1426 |  |  |  |  |  |  |
|  |  |  |  |  | 153 | 610107C00-012-G |  | RES,10KOhm,+/-5%,1/16W,G,SMD0402 | WALSIN TECHNOLOGY CORPORATION | WR04X103JTL |  | G |  |  |  |  |  |  |  |
|  |  |  |  |  | 153 | 610107C00-011-G |  | RES,10KOhm,+/-5%,1/16W,G,SMD0402 | YAGEO CORPORATION COMPONENT | RC0402JR-0710KL |  | G |  |  |  |  |  |  |  |
|  |  |  |  |  | 153 | 610107C00-044-G |  | RES,10KOhm,+/-5%,1/16W,G,SMD0402 | TA-I TECHNOLOGY CO., LTD. | RM04JTN103 |  | G |  |  |  |  |  |  |  |
|  |  |  |  |  | 153 | 610107C00-024-G |  | RES,10KOhm,+/-5%,1/16W,G,SMD0402 | PANASONIC INDUSTRIAL CO.,LTD. | ERJ2GEJ103X |  | G |  |  |  |  |  |  |  |
|  |  |  |  |  | 153 | 610107C00-029-G |  | RES,10KOhm,+/-5%,1/16W,G,SMD0402 | VISHAY ENTER TECHNO LOGY.INC | CRCW040210K0JNED |  | G |  |  |  |  |  |  |  |
|  |  |  |  | 154 | 154 | 610118100-017-G | - | RES,1.4KOhm,+/-1%,1/16W,G,SMD0402 | KOA SPEER ELECTRONICS, INC. | RK73H1ETTP1401F | 4 | G | R1529,R1530,R1531,R1532 |  |  |  |  |  |  |
|  |  |  |  |  | 154 | 610118100-012-G |  | RES,1.4KOhm,+/-1%,1/16W,G,SMD0402 | WALSIN TECHNOLOGY CORPORATION | WR04X1401FTL |  | G |  |  |  |  |  |  |  |
|  |  |  |  |  | 154 | 610118100-011-G |  | RES,1.4KOhm,+/-1%,1/16W,G,SMD0402 | YAGEO CORPORATION COMPONENT | RC0402FR-071K4L |  | G |  |  |  |  |  |  |  |
|  |  |  |  |  | 154 | 610118100-044-G |  | RES,1.4KOhm,+/-1%,1/16W,G,SMD0402 | TA-I TECHNOLOGY CO., LTD | RM04FTN1401 |  | G |  |  |  |  |  |  |  |
|  |  |  |  |  | 154 | 610118100-024-G |  | RES,1.4KOhm,+/-1%,1/16W,G,SMD0402 | PANASONIC INDUSTRIAL CO.,LTD. | ERJ2RKF1401X |  | G |  |  |  |  |  |  |  |
|  |  |  |  | 155 | 155 | 21050LA00-217-G |  | IC,IDT,5V41234NLGI8,G,VFQFPN-16,SMD | INTEGRATED DEVICE TECHNOLOGY | 5V41234NLGI8 | 1 | G | U_CLKGEN |  |  |  |  |  |  |
|  |  |  |  | 156 | 156 | 41050R700-396-G |  | Flash,S29GL128S10TFIV20,2.7~3.6V,128M,CFI,G,TSOP-56,SMD | SPANSION INTERNATIONAL LLC | S29GL128S10TFIV20 | 1 | G | U_EXP_FLASH1 |  |  |  |  |  |  |
|  |  |  |  | 157 | 157 | 41040DK00-191-G |  | EEPROM,AT24C04C-SSHM-T,1.7~5.5V,4K,2-wire,G,SOIC-8,SMD | ATMEL CORPORATION | AT24C04C-SSHM-T | 1 | G | U_EXP_FRU1 |  |  |  |  |  |  |
|  |  |  |  | 158 | 158 | 41040HW00-191-G |  | EEPROM,AT24C02D-SSHM-T,1.7~3.6V,2K,I2C,G,SOIC-8,SMD | ATMEL CORPORATION | AT24C02D-SSHM-T | 1 | G | U_EXP_FRU2 |  |  |  |  |  |  |
|  |  |  |  | 159 | 159 | 420103500-18R-G |  | SRAM,MR0D08BMA45R,3.3V,128K*8,G,FBGA-48,SMD | Everspin Technologies, Inc. | MR0D08BMA45R | 1 | G | U_EXP_NVSRAM1 |  |  |  |  |  |  |
|  |  |  |  | 160 | 160 | 311004V00-223-G |  | Logic IC,Translator,PCA9617ADMR2G,Vcca=0.8V~5.5V,Vccb=2.2V~5.5V,102ns,Micro8,8P,G | ON SEMICONDUCTOR CORP | PCA9617ADMR2G | 2 | G | U8,U_I2C_RE1 |  |  |  |  |  |  |
|  |  |  |  | 161 | 161 | 210826W00-283-G |  | IC,BROADCOM,PEX9797-AA80BCG,AA,G,FCBGA-1156,SMD | BROADCOM SINGAPORE PTE LTD. | SS14-0B00-00 | 1 | G | U_PEX_SW1 |  |  |  |  |  |  |
|  |  |  |  | 162 | 162 | 310101400-031-G | - | IC,Gate&Inverter,74LVC1G08GW,1.65~5.5V,G,SOT353-5,SMD | NXP SEMICONDUCTORS | 74LVC1G08GW | 2 | G | U2,U108 |  |  |  |  |  |  |
|  |  |  |  | 163 | 163 | 210828A00-GUW-G |  | IC,AVAGO,SX00-0B00-00,G,fpBGA-1197,SMD | AVAGO TECHNOLOGIES INTERNATION/AGILENT SEMICONDUCTOR | SX00-0B00-00 | 1 | G | U3 |  |  |  |  |  |  |
|  |  |  |  | 164 | 164 | 32020WJ00-183-G | - | IC,Power Controller,TPS3808G01DBVR,G,SOT23-6,SMD | TEXAS INSTRUMENTS | TPS3808G01DBVR | 1 | G | U4 |  |  |  |  |  |  |
|  |  |  |  | 165 | 165 | 32022FF00-173-G |  | IC,Power Controller,MAX6315US29D1+T,G,SOT-143-4,SMD | MAXIM INTEGRATED PRODUCTS, INC. | MAX6315US29D1+T | 1 | G | U6 |  |  |  |  |  |  |
|  |  |  |  | 166 | 166 | 41040G200-214-G |  | EEPROM,M95256-RMN6TP,1.8~5.5V,256K,SPI,G,SO-8,SMD | ST MICRO ELECTRONICS,INC | M95256-RMN6TP | 2 | G | U9,U117 |  |  |  |  |  |  |
|  |  |  |  | 167 | 167 | 310408900-217-G | - | IC,Switch,74CBTLV3257PGG8,2.3~3.6V,G,TSSOP-16,SMD | INTEGRATED DEVICE TECHNOLOGY | 74CBTLV3257PGG8 | 1 | G | U27 |  |  |  |  |  |  |
|  |  |  |  | 168 | 168 | 31050CU00-131-G |  | IC,Buffer,TC7SZ07FU,1.65~5.5V,G,SSOP-5,SMD | TOSHIBA ELECTRONICS ASIA LTD | TC7SZ07FU | 2 | G | U107,U110 |  |  |  |  |  |  |
|  |  |  |  | 169 | 169 | 310507Q00-223-G |  | Logic IC,Buffer,NL17SZ17DFT2G,1.65V~5.5V,15ns,SC-88A/SOT-353,5P,G | ON SEMICONDUCTOR CORP | NL17SZ17DFT2G | 1 | G | U109 |  |  |  |  |  |  |
|  |  |  |  | 170 | 170 | 710124Y00-100-G |  | XTAL,25MHz,+/-20ppm,20pF,G,SMD | TXC CORPORATION | 7M25020015 | 1 | G | X1 |  |  |  |  |  |  |
|  |  |  |  | 171 | 171 | 71020C700-621-G | - | OSC,150MHz,+/-50ppm,3.3V,50ohm,G,SMD | FOX ELECTRONICS INC | 774-150-8 | 1 | G | Y1 |  |  |  |  |  |  |
|  |  |  |  | 172 | 172 | 340718A00-245-G |  | CONN,SAS,V/T,0.6mm,30u,G,SMD-74 | AMPHENOL SHANGHAI CORP. | U10-B074-250T | 12 | G | J_PCIE_OUT1,J_PCIE_IN1,J_PCIE_OUT2,J_PCIE_IN2,J_PCIE_OUT3,J_PCIE_OUT4,J4,J_PCIE_OUT5,J5,J_PCIE_OUT6,J6,J_PCIE_OUT7 |  |  |  |  |  |  |
|  |  |  |  | 173 | 173 | 34066Q200-317-G |  | CONN,Header,Power,2X8,V/T,Bla,3mm,G,DIP-16 | MOLEX INCORPORATED | 43045-1627 | 1 | G | J_PWR_BP |  |  |  |  |  |  |
|  |  |  |  | 174 | 174 | 340636700-600-G |  | CONN,Header,Power,2X8,V/T,Whi,4.2mm,G,DIP-16 | FOXCONN TECHNOLOGY CO.,LTD. | HM3508E-HP1 | 1 | G | J_PWR_IN |  |  |  |  |  |  |
|  |  |  |  | 175 | 175 | 340716800-245-G |  | CONN,SAS,V/T,Bla,0.75mm,30u,G,SMD-72 | AMPHENOL SHANGHAI CORP. | G40H4232212HR | 1 | G | J_SAS_IN1 |  |  |  |  |  |  |
|  |  |  |  | 176 | 176 | 340626400-600-G |  | CONN,Header,Shrouded,1X4,V/T,1mm,Ivo,G,SMD-4 | FOXCONN TECHNOLOGY CO.,LTD. | HS6104E | 2 | G | J_UART1,J_SMART1 |  |  |  |  |  |  |
|  |  |  |  | 177 | 177 | 3406ALW00-317-G |  | CONN,Header,Shrouded,2X5,V/T,Bla,2mm,30u,G,SMD-10 | MOLEX INCORPORATED | 87832-5423 | 1 | G | J3 |  |  |  |  |  |  |
|  |  |  |  | 178 | 178 | 34045GE00-GRS-G |  | CONN,SPI FLASH SOCKET,Bla,1.27mm,15u,G,SMD-8 | LOTES CO LTD | ASPI0001-P002A | 1 | G | U10 |  |  |  |  |  |  |
